FILE_TYPE = MACRO_DRAWING;
SET COLOR_WIRE YELLOW;
SET COLOR_PROP MONO;
SET COLOR_DOT WHITE;
SET COLOR_ARC YELLOW;
SET COLOR_BODY GREEN;
SET COLOR_NOTE MONO;
SET PROP_DISPLAY VALUE;
SET PAGE_NUMBER P225;
FORCEADD PVDDQ_GHJ..1
(2550 2000);
FORCEPROP 3 LASTPIN (2550 1950) SIG_NAME PVDDQ_GHJ\g
J 0
(2560 1960);
DISPLAY 0.659574 (2560 1960);
PAINT MONO (2560 1960);
DISPLAY INVISIBLE (2560 1960);
FORCEPROP 1 LAST BODY_TYPE PLUMBING
J 0
(2505 1957);
DISPLAY 0.340426 (2505 1957);
PAINT GREEN (2505 1957);
DISPLAY INVISIBLE (2505 1957);
FORCEPROP 2 LAST CDS_LIB mstr_symbols
J 0
(2550 2000);
PAINT ORANGE (2550 2000);
DISPLAY INVISIBLE (2550 2000);
FORCEPROP 1 LAST VOLTAGE 1.2V
J 0
(2505 1957);
DISPLAY 0.340426 (2505 1957);
PAINT SKYBLUE (2505 1957);
DISPLAY INVISIBLE (2505 1957);
FORCEPROP 1 LAST PATH I109
J 0
(2600 2025);
DISPLAY 0.872340 (2600 2025);
PAINT AQUA (2600 2025);
DISPLAY INVISIBLE (2600 2025);
FORCEPROP 1 LAST HDL_POWER PVDDQ_GHJ
J 1
(2550 2050);
DISPLAY 0.872340 (2550 2050);
PAINT GREEN (2550 2050);
DISPLAY INVISIBLE (2550 2050);
FORCEPROP 2 LAST BOM_COST MEM_VRD_PVDDQ_CD
J 0
(2625 2100);
PAINT MONO (2625 2100);
DISPLAY INVISIBLE (2625 2100);
FORCEPROP 2 LAST ROOM VDDQ_GHJ_PWR_VR
J 0
(2800 2100);
PAINT ORANGE (2800 2100);
DISPLAY INVISIBLE (2800 2100);
FORCEADD CAP..1
(2400 2825);
FORCEPROP 1 LASTPIN (2400 2725) $PN 2
J 0
(2410 2705);
DISPLAY 0.617021 (2410 2705);
PAINT ORANGE (2410 2705);
FORCEPROP 1 LAST MATERIAL X5R
J 0
(2450 2725);
DISPLAY 0.617021 (2450 2725);
PAINT SKYBLUE (2450 2725);
FORCEPROP 1 LAST TOLERANCE 20%
J 0
(2450 2775);
DISPLAY 0.617021 (2450 2775);
PAINT SKYBLUE (2450 2775);
FORCEPROP 1 LASTPIN (2400 2925) $PN 1
J 0
(2410 2905);
DISPLAY 0.617021 (2410 2905);
PAINT ORANGE (2410 2905);
FORCEPROP 1 LAST VOLTAGE 4V
J 0
(2450 2825);
DISPLAY 0.617021 (2450 2825);
PAINT SKYBLUE (2450 2825);
FORCEPROP 1 LAST LOCATION C2G16
J 0
(2450 2925);
DISPLAY 0.617021 (2450 2925);
PAINT AQUA (2450 2925);
FORCEPROP 1 LAST PART_NUMBER 602433-112
J 0
(2450 2675);
DISPLAY 0.617021 (2450 2675);
PAINT BLUE (2450 2675);
FORCEPROP 1 LAST VALUE 100UF
J 0
(2450 2875);
DISPLAY 0.617021 (2450 2875);
PAINT SKYBLUE (2450 2875);
FORCEPROP 1 LAST PACK_TYPE 0805
J 0
(2450 2625);
DISPLAY 0.617021 (2450 2625);
PAINT SKYBLUE (2450 2625);
FORCEPROP 2 LAST CDS_LIB mstr_discrete
J 0
(2400 2825);
PAINT MONO (2400 2825);
DISPLAY INVISIBLE (2400 2825);
FORCEPROP 2 LAST CDS_LOCATION C2G16
J 0
(2450 2925);
DISPLAY 0.617021 (2450 2925);
PAINT AQUA (2450 2925);
DISPLAY INVISIBLE (2450 2925);
FORCEPROP 1 LAST PATH I110
J 0
(2450 2975);
DISPLAY 0.978723 (2450 2975);
PAINT WHITE (2450 2975);
DISPLAY INVISIBLE (2450 2975);
FORCEPROP 2 LAST SEC 1
J 0
(2450 3025);
DISPLAY 0.680851 (2450 3025);
PAINT MONO (2450 3025);
DISPLAY INVISIBLE (2450 3025);
FORCEPROP 2 LAST BOM_COST MEM_VRD_PVDDQ_CD
J 0
(2450 2975);
PAINT MONO (2450 2975);
DISPLAY INVISIBLE (2450 2975);
FORCEPROP 2 LAST SEC_TYPE 0805
J 0
(2450 3025);
DISPLAY 1.021277 (2450 3025);
PAINT ORANGE (2450 3025);
DISPLAY INVISIBLE (2450 3025);
FORCEPROP 2 LAST ROOM VDDQ_GHJ_PWR_VR
J 0
(2450 2975);
PAINT MONO (2450 2975);
DISPLAY INVISIBLE (2450 2975);
FORCEADD GND..1
(4275 1350);
FORCEPROP 3 LASTPIN (4275 1400) SIG_NAME GND\g
J 0
(4285 1410);
DISPLAY 0.659574 (4285 1410);
PAINT MONO (4285 1410);
DISPLAY INVISIBLE (4285 1410);
FORCEPROP 2 LAST ROOM VDDQ_GHJ_PWR_VR
J 0
(3725 1425);
PAINT ORANGE (3725 1425);
DISPLAY INVISIBLE (3725 1425);
FORCEPROP 2 LAST BOM_COST MEM_VRD_PVDDQ_CD
J 0
(3950 1425);
PAINT MONO (3950 1425);
DISPLAY INVISIBLE (3950 1425);
FORCEPROP 1 LAST VOLTAGE 0
J 0
(4275 1350);
PAINT SKYBLUE (4275 1350);
DISPLAY INVISIBLE (4275 1350);
FORCEPROP 2 LAST CDS_LIB mstr_symbols
J 0
(4275 1350);
PAINT ORANGE (4275 1350);
DISPLAY INVISIBLE (4275 1350);
FORCEPROP 1 LAST SIZE 1B
J 0
(4350 1300);
DISPLAY 0.893617 (4350 1300);
PAINT GREEN (4350 1300);
DISPLAY INVISIBLE (4350 1300);
FORCEPROP 1 LAST BODY_TYPE PLUMBING
J 0
(4230 1307);
DISPLAY 0.340426 (4230 1307);
PAINT GREEN (4230 1307);
DISPLAY INVISIBLE (4230 1307);
FORCEPROP 1 LAST PATH I114
J 0
(4350 1350);
DISPLAY 1.170213 (4350 1350);
PAINT AQUA (4350 1350);
DISPLAY INVISIBLE (4350 1350);
FORCEPROP 1 LAST HDL_POWER GND
J 0
(4275 1500);
DISPLAY 0.893617 (4275 1500);
PAINT GREEN (4275 1500);
DISPLAY INVISIBLE (4275 1500);
FORCEADD VCC_CORE..1
(-1250 1575);
FORCEPROP 3 LASTPIN (-1250 1525) SIG_NAME VR_FET_SW_P12V_STBY_PVDDQ_GHJ\g
J 0
(-1240 1535);
DISPLAY 0.659574 (-1240 1535);
PAINT MONO (-1240 1535);
DISPLAY INVISIBLE (-1240 1535);
FORCEPROP 1 LAST HDL_POWER VR_FET_SW_P12V_STBY_PVDDQ_GHJ
J 1
(-1250 1625);
DISPLAY 0.617021 (-1250 1625);
PAINT GREEN (-1250 1625);
FORCEPROP 2 LAST CDS_LIB mstr_symbols
J 0
(-1250 1575);
PAINT ORANGE (-1250 1575);
DISPLAY INVISIBLE (-1250 1575);
FORCEPROP 1 LAST PATH I120
J 0
(-1200 1600);
DISPLAY 1.170213 (-1200 1600);
PAINT AQUA (-1200 1600);
DISPLAY INVISIBLE (-1200 1600);
FORCEADD GND..1
(-1250 825);
FORCEPROP 3 LASTPIN (-1250 875) SIG_NAME GND\g
J 0
(-1240 885);
DISPLAY 0.659574 (-1240 885);
PAINT MONO (-1240 885);
DISPLAY INVISIBLE (-1240 885);
FORCEPROP 2 LAST BOM_COST MEM_VRD_PVDDQ_CD
J 0
(-1575 900);
PAINT MONO (-1575 900);
DISPLAY INVISIBLE (-1575 900);
FORCEPROP 2 LAST ROOM VDDQ_GHJ_PWR_VR
J 0
(-1800 900);
PAINT ORANGE (-1800 900);
DISPLAY INVISIBLE (-1800 900);
FORCEPROP 1 LAST BODY_TYPE PLUMBING
J 0
(-1295 782);
DISPLAY 0.340426 (-1295 782);
PAINT GREEN (-1295 782);
DISPLAY INVISIBLE (-1295 782);
FORCEPROP 1 LAST VOLTAGE 0
J 0
(-1250 825);
PAINT SKYBLUE (-1250 825);
DISPLAY INVISIBLE (-1250 825);
FORCEPROP 1 LAST SIZE 1B
J 0
(-1175 775);
DISPLAY 0.893617 (-1175 775);
PAINT GREEN (-1175 775);
DISPLAY INVISIBLE (-1175 775);
FORCEPROP 2 LAST CDS_LIB mstr_symbols
J 0
(-1250 825);
PAINT ORANGE (-1250 825);
DISPLAY INVISIBLE (-1250 825);
FORCEPROP 1 LAST PATH I123
J 0
(-1175 825);
DISPLAY 1.170213 (-1175 825);
PAINT AQUA (-1175 825);
DISPLAY INVISIBLE (-1175 825);
FORCEPROP 1 LAST HDL_POWER GND
J 0
(-1250 975);
DISPLAY 0.893617 (-1250 975);
PAINT GREEN (-1250 975);
DISPLAY INVISIBLE (-1250 975);
FORCEADD INDUCTOR..1
(-1675 1375);
FORCEPROP 1 LAST VALUE 100NH
J 2
(-1680 1290);
DISPLAY 0.617021 (-1680 1290);
PAINT SKYBLUE (-1680 1290);
FORCEPROP 1 LASTPIN (-1775 1375) $PN 1
J 0
(-1775 1385);
DISPLAY 0.617021 (-1775 1385);
PAINT WHITE (-1775 1385);
FORCEPROP 1 LAST LOCATION L1F1
J 0
(-1775 1425);
DISPLAY 0.617021 (-1775 1425);
PAINT AQUA (-1775 1425);
FORCEPROP 1 LAST MATERIAL IND
J 0
(-1660 1290);
DISPLAY 0.617021 (-1660 1290);
PAINT SKYBLUE (-1660 1290);
FORCEPROP 1 LASTPIN (-1575 1375) $PN 2
J 2
(-1565 1385);
DISPLAY 0.617021 (-1565 1385);
PAINT WHITE (-1565 1385);
FORCEPROP 1 LAST PART_NUMBER D92183-020
J 0
(-1775 1475);
DISPLAY 0.617021 (-1775 1475);
PAINT BLUE (-1775 1475);
FORCEPROP 1 LAST PACK_TYPE SM
J 0
(-1385 1290);
DISPLAY 0.617021 (-1385 1290);
PAINT SKYBLUE (-1385 1290);
FORCEPROP 2 LAST CDS_LIB mstr_discrete
J 0
(-1675 1375);
PAINT ORANGE (-1675 1375);
DISPLAY INVISIBLE (-1675 1375);
FORCEPROP 2 LAST CDS_LOCATION L1F1
J 0
(-1775 1425);
DISPLAY 0.617021 (-1775 1425);
PAINT AQUA (-1775 1425);
DISPLAY INVISIBLE (-1775 1425);
FORCEPROP 2 LAST BOM_COST MEM_VRD_PVDDQ_CD
J 0
(-1775 1525);
PAINT MONO (-1775 1525);
DISPLAY INVISIBLE (-1775 1525);
FORCEPROP 1 LAST PATH I124
J 0
(-1775 1525);
DISPLAY 1.319149 (-1775 1525);
PAINT ORANGE (-1775 1525);
DISPLAY INVISIBLE (-1775 1525);
FORCEPROP 2 LAST ROOM VDDQ_GHJ_PWR_VR
J 0
(-1775 1525);
PAINT MONO (-1775 1525);
DISPLAY INVISIBLE (-1775 1525);
FORCEPROP 2 LAST SEC_TYPE SM
J 0
(-1770 1595);
DISPLAY 1.021277 (-1770 1595);
PAINT ORANGE (-1770 1595);
DISPLAY INVISIBLE (-1770 1595);
FORCEPROP 2 LAST SEC 1
J 0
(-1770 1595);
DISPLAY 0.680851 (-1770 1595);
PAINT MONO (-1770 1595);
DISPLAY INVISIBLE (-1770 1595);
FORCEADD P12V_STBY..1
(-2000 1575);
FORCEPROP 3 LASTPIN (-2000 1525) SIG_NAME P12V_STBY\g
J 0
(-1990 1535);
DISPLAY 0.659574 (-1990 1535);
PAINT MONO (-1990 1535);
DISPLAY INVISIBLE (-1990 1535);
FORCEPROP 1 LAST HDL_POWER P12V_STBY
J 0
(-2300 1450);
DISPLAY 0.872340 (-2300 1450);
PAINT ORANGE (-2300 1450);
DISPLAY INVISIBLE (-2300 1450);
FORCEPROP 1 LAST VOLTAGE 12.0V
J 0
(-2045 1532);
DISPLAY 0.340426 (-2045 1532);
PAINT SKYBLUE (-2045 1532);
DISPLAY INVISIBLE (-2045 1532);
FORCEPROP 1 LAST BODY_TYPE PLUMBING
J 0
(-2045 1532);
DISPLAY 0.340426 (-2045 1532);
PAINT GREEN (-2045 1532);
DISPLAY INVISIBLE (-2045 1532);
FORCEPROP 1 LAST SIZE 1B
J 0
(-1955 1597);
DISPLAY 0.340426 (-1955 1597);
PAINT GREEN (-1955 1597);
DISPLAY INVISIBLE (-1955 1597);
FORCEPROP 2 LAST CDS_LIB mstr_symbols
J 0
(-2000 1575);
PAINT ORANGE (-2000 1575);
DISPLAY INVISIBLE (-2000 1575);
FORCEPROP 1 LAST PATH I176
J 0
(-1955 1577);
DISPLAY 0.340426 (-1955 1577);
PAINT GREEN (-1955 1577);
DISPLAY INVISIBLE (-1955 1577);
FORCEADD CAP..1
(-1950 3050);
FORCEPROP 1 LAST TOLERANCE 20%
J 0
(-1900 3000);
DISPLAY 0.617021 (-1900 3000);
PAINT SKYBLUE (-1900 3000);
FORCEPROP 1 LAST MATERIAL X6S
J 0
(-1900 2950);
DISPLAY 0.617021 (-1900 2950);
PAINT SKYBLUE (-1900 2950);
FORCEPROP 1 LASTPIN (-1950 2950) $PN 2
J 0
(-1940 2930);
DISPLAY 0.617021 (-1940 2930);
PAINT ORANGE (-1940 2930);
FORCEPROP 1 LAST PART_NUMBER C95333-002
J 0
(-1900 2900);
DISPLAY 0.617021 (-1900 2900);
PAINT BLUE (-1900 2900);
FORCEPROP 1 LAST PACK_TYPE 0805LF
J 0
(-1900 2850);
DISPLAY 0.617021 (-1900 2850);
PAINT SKYBLUE (-1900 2850);
FORCEPROP 1 LASTPIN (-1950 3150) $PN 1
J 0
(-1940 3130);
DISPLAY 0.617021 (-1940 3130);
PAINT ORANGE (-1940 3130);
FORCEPROP 1 LAST LOCATION C8P31
J 0
(-1900 3150);
DISPLAY 0.617021 (-1900 3150);
PAINT AQUA (-1900 3150);
FORCEPROP 1 LAST VALUE 22UF
J 0
(-1900 3100);
DISPLAY 0.617021 (-1900 3100);
PAINT SKYBLUE (-1900 3100);
FORCEPROP 1 LAST VOLTAGE 4V
J 0
(-1900 3050);
PAINT SKYBLUE (-1900 3050);
DISPLAY INVISIBLE (-1900 3050);
FORCEPROP 2 LAST CDS_LIB mstr_discrete
J 0
(-1950 3050);
PAINT ORANGE (-1950 3050);
DISPLAY INVISIBLE (-1950 3050);
FORCEPROP 2 LAST BOM_COST MEM_VRD_PVDDQ_GHJ
J 0
(-1900 3200);
PAINT MONO (-1900 3200);
DISPLAY INVISIBLE (-1900 3200);
FORCEPROP 2 LAST SEC_TYPE 0805LF
J 0
(-1900 3250);
DISPLAY 1.021277 (-1900 3250);
PAINT ORANGE (-1900 3250);
DISPLAY INVISIBLE (-1900 3250);
FORCEPROP 2 LAST SEC 1
J 0
(-1900 3250);
DISPLAY 0.680851 (-1900 3250);
PAINT MONO (-1900 3250);
DISPLAY INVISIBLE (-1900 3250);
FORCEPROP 2 LAST CDS_LOCATION C8P31
J 0
(-1900 3150);
DISPLAY 0.617021 (-1900 3150);
PAINT AQUA (-1900 3150);
DISPLAY INVISIBLE (-1900 3150);
FORCEPROP 1 LAST PATH I178
J 0
(-1900 3200);
DISPLAY 0.978723 (-1900 3200);
PAINT WHITE (-1900 3200);
DISPLAY INVISIBLE (-1900 3200);
FORCEPROP 2 LAST ROOM VDDQ_GHJ_CPU1
J 0
(-1900 3200);
PAINT MONO (-1900 3200);
DISPLAY INVISIBLE (-1900 3200);
FORCEADD CAP..1
(-1550 3050);
FORCEPROP 1 LASTPIN (-1550 2950) $PN 2
J 0
(-1540 2930);
DISPLAY 0.617021 (-1540 2930);
PAINT ORANGE (-1540 2930);
FORCEPROP 1 LAST TOLERANCE 20%
J 0
(-1500 3000);
DISPLAY 0.617021 (-1500 3000);
PAINT SKYBLUE (-1500 3000);
FORCEPROP 1 LAST PACK_TYPE 0603LF
J 0
(-1500 2850);
DISPLAY 0.617021 (-1500 2850);
PAINT SKYBLUE (-1500 2850);
FORCEPROP 1 LAST MATERIAL X6S
J 0
(-1500 2950);
DISPLAY 0.617021 (-1500 2950);
PAINT SKYBLUE (-1500 2950);
FORCEPROP 1 LAST PART_NUMBER E15431-001
J 0
(-1500 2900);
DISPLAY 0.617021 (-1500 2900);
PAINT BLUE (-1500 2900);
FORCEPROP 1 LAST VOLTAGE 4V
J 0
(-1500 3050);
DISPLAY 0.617021 (-1500 3050);
PAINT SKYBLUE (-1500 3050);
FORCEPROP 1 LAST VALUE 10UF
J 0
(-1500 3100);
DISPLAY 0.617021 (-1500 3100);
PAINT SKYBLUE (-1500 3100);
FORCEPROP 1 LASTPIN (-1550 3150) $PN 1
J 0
(-1540 3130);
DISPLAY 0.617021 (-1540 3130);
PAINT ORANGE (-1540 3130);
FORCEPROP 1 LAST LOCATION C2D43
J 0
(-1500 3150);
DISPLAY 0.617021 (-1500 3150);
PAINT AQUA (-1500 3150);
FORCEPROP 2 LAST CDS_LIB mstr_discrete
J 0
(-1550 3050);
PAINT ORANGE (-1550 3050);
DISPLAY INVISIBLE (-1550 3050);
FORCEPROP 2 LAST SEC_TYPE 0603LF
J 0
(-1500 3250);
DISPLAY 1.021277 (-1500 3250);
PAINT ORANGE (-1500 3250);
DISPLAY INVISIBLE (-1500 3250);
FORCEPROP 2 LAST BOM_COST MEM_VRD_PVDDQ_GHJ
J 0
(-1500 3200);
PAINT MONO (-1500 3200);
DISPLAY INVISIBLE (-1500 3200);
FORCEPROP 2 LAST SEC 1
J 0
(-1500 3250);
DISPLAY 0.680851 (-1500 3250);
PAINT MONO (-1500 3250);
DISPLAY INVISIBLE (-1500 3250);
FORCEPROP 2 LAST CDS_LOCATION C2D43
J 0
(-1500 3150);
DISPLAY 0.617021 (-1500 3150);
PAINT AQUA (-1500 3150);
DISPLAY INVISIBLE (-1500 3150);
FORCEPROP 1 LAST PATH I179
J 0
(-1500 3200);
DISPLAY 0.978723 (-1500 3200);
PAINT WHITE (-1500 3200);
DISPLAY INVISIBLE (-1500 3200);
FORCEPROP 2 LAST ROOM VDDQ_GHJ_CPU1
J 0
(-1500 3200);
PAINT MONO (-1500 3200);
DISPLAY INVISIBLE (-1500 3200);
FORCEADD CAP..1
(-1200 3050);
FORCEPROP 1 LASTPIN (-1200 2950) $PN 2
J 0
(-1190 2930);
DISPLAY 0.617021 (-1190 2930);
PAINT ORANGE (-1190 2930);
FORCEPROP 1 LAST MATERIAL X6S
J 0
(-1150 2950);
DISPLAY 0.617021 (-1150 2950);
PAINT SKYBLUE (-1150 2950);
FORCEPROP 1 LAST TOLERANCE 20%
J 0
(-1150 3000);
DISPLAY 0.617021 (-1150 3000);
PAINT SKYBLUE (-1150 3000);
FORCEPROP 1 LAST VOLTAGE 4V
J 0
(-1150 3050);
DISPLAY 0.617021 (-1150 3050);
PAINT SKYBLUE (-1150 3050);
FORCEPROP 1 LASTPIN (-1200 3150) $PN 1
J 0
(-1190 3130);
DISPLAY 0.617021 (-1190 3130);
PAINT ORANGE (-1190 3130);
FORCEPROP 1 LAST VALUE 10UF
J 0
(-1150 3100);
DISPLAY 0.617021 (-1150 3100);
PAINT SKYBLUE (-1150 3100);
FORCEPROP 1 LAST LOCATION C2D41
J 0
(-1150 3150);
DISPLAY 0.617021 (-1150 3150);
PAINT AQUA (-1150 3150);
FORCEPROP 1 LAST PART_NUMBER E15431-001
J 0
(-1150 2900);
DISPLAY 0.617021 (-1150 2900);
PAINT BLUE (-1150 2900);
FORCEPROP 1 LAST PACK_TYPE 0603LF
J 0
(-1150 2850);
DISPLAY 0.617021 (-1150 2850);
PAINT SKYBLUE (-1150 2850);
FORCEPROP 2 LAST CDS_LIB mstr_discrete
J 0
(-1200 3050);
PAINT ORANGE (-1200 3050);
DISPLAY INVISIBLE (-1200 3050);
FORCEPROP 2 LAST SEC_TYPE 0603LF
J 0
(-1150 3250);
DISPLAY 1.021277 (-1150 3250);
PAINT ORANGE (-1150 3250);
DISPLAY INVISIBLE (-1150 3250);
FORCEPROP 2 LAST BOM_COST MEM_VRD_PVDDQ_GHJ
J 0
(-1150 3200);
PAINT MONO (-1150 3200);
DISPLAY INVISIBLE (-1150 3200);
FORCEPROP 2 LAST SEC 1
J 0
(-1150 3250);
DISPLAY 0.680851 (-1150 3250);
PAINT MONO (-1150 3250);
DISPLAY INVISIBLE (-1150 3250);
FORCEPROP 2 LAST CDS_LOCATION C2D41
J 0
(-1150 3150);
DISPLAY 0.617021 (-1150 3150);
PAINT AQUA (-1150 3150);
DISPLAY INVISIBLE (-1150 3150);
FORCEPROP 1 LAST PATH I180
J 0
(-1150 3200);
DISPLAY 0.978723 (-1150 3200);
PAINT WHITE (-1150 3200);
DISPLAY INVISIBLE (-1150 3200);
FORCEPROP 2 LAST ROOM VDDQ_GHJ_CPU1
J 0
(-1150 3200);
PAINT MONO (-1150 3200);
DISPLAY INVISIBLE (-1150 3200);
FORCEADD CAP..1
(-850 3050);
FORCEPROP 1 LASTPIN (-850 2950) $PN 2
J 0
(-840 2930);
DISPLAY 0.617021 (-840 2930);
PAINT ORANGE (-840 2930);
FORCEPROP 1 LAST PART_NUMBER E15431-001
J 0
(-800 2900);
DISPLAY 0.617021 (-800 2900);
PAINT BLUE (-800 2900);
FORCEPROP 1 LAST VOLTAGE 4V
J 0
(-800 3050);
DISPLAY 0.617021 (-800 3050);
PAINT SKYBLUE (-800 3050);
FORCEPROP 1 LASTPIN (-850 3150) $PN 1
J 0
(-840 3130);
DISPLAY 0.617021 (-840 3130);
PAINT ORANGE (-840 3130);
FORCEPROP 1 LAST VALUE 10UF
J 0
(-800 3100);
DISPLAY 0.617021 (-800 3100);
PAINT SKYBLUE (-800 3100);
FORCEPROP 1 LAST LOCATION C2D44
J 0
(-800 3150);
DISPLAY 0.617021 (-800 3150);
PAINT AQUA (-800 3150);
FORCEPROP 1 LAST PACK_TYPE 0603LF
J 0
(-800 2850);
DISPLAY 0.617021 (-800 2850);
PAINT SKYBLUE (-800 2850);
FORCEPROP 1 LAST MATERIAL X6S
J 0
(-800 2950);
DISPLAY 0.617021 (-800 2950);
PAINT SKYBLUE (-800 2950);
FORCEPROP 1 LAST TOLERANCE 20%
J 0
(-800 3000);
DISPLAY 0.617021 (-800 3000);
PAINT SKYBLUE (-800 3000);
FORCEPROP 2 LAST CDS_LIB mstr_discrete
J 0
(-850 3050);
PAINT ORANGE (-850 3050);
DISPLAY INVISIBLE (-850 3050);
FORCEPROP 2 LAST CDS_LOCATION C2D44
J 0
(-800 3150);
DISPLAY 0.617021 (-800 3150);
PAINT AQUA (-800 3150);
DISPLAY INVISIBLE (-800 3150);
FORCEPROP 2 LAST ROOM VDDQ_GHJ_CPU1
J 0
(-800 3200);
PAINT MONO (-800 3200);
DISPLAY INVISIBLE (-800 3200);
FORCEPROP 1 LAST PATH I181
J 0
(-800 3200);
DISPLAY 0.978723 (-800 3200);
PAINT WHITE (-800 3200);
DISPLAY INVISIBLE (-800 3200);
FORCEPROP 2 LAST BOM_COST MEM_VRD_PVDDQ_GHJ
J 0
(-800 3200);
PAINT MONO (-800 3200);
DISPLAY INVISIBLE (-800 3200);
FORCEPROP 2 LAST SEC 1
J 0
(-800 3250);
DISPLAY 0.680851 (-800 3250);
PAINT MONO (-800 3250);
DISPLAY INVISIBLE (-800 3250);
FORCEPROP 2 LAST SEC_TYPE 0603LF
J 0
(-800 3250);
DISPLAY 1.021277 (-800 3250);
PAINT ORANGE (-800 3250);
DISPLAY INVISIBLE (-800 3250);
FORCEADD GND..1
(-450 2675);
FORCEPROP 3 LASTPIN (-450 2725) SIG_NAME GND\g
J 0
(-440 2735);
DISPLAY 0.659574 (-440 2735);
PAINT MONO (-440 2735);
DISPLAY INVISIBLE (-440 2735);
FORCEPROP 2 LAST BOM_COST MEM_VRD_PVDDQ_CD
J 0
(-775 2750);
PAINT MONO (-775 2750);
DISPLAY INVISIBLE (-775 2750);
FORCEPROP 2 LAST ROOM VDDQ_ABC_PWR_VR
J 0
(-1000 2750);
PAINT ORANGE (-1000 2750);
DISPLAY INVISIBLE (-1000 2750);
FORCEPROP 1 LAST BODY_TYPE PLUMBING
J 0
(-495 2632);
DISPLAY 0.340426 (-495 2632);
PAINT GREEN (-495 2632);
DISPLAY INVISIBLE (-495 2632);
FORCEPROP 1 LAST VOLTAGE 0
J 0
(-450 2675);
PAINT SKYBLUE (-450 2675);
DISPLAY INVISIBLE (-450 2675);
FORCEPROP 2 LAST CDS_LIB mstr_symbols
J 0
(-450 2675);
PAINT ORANGE (-450 2675);
DISPLAY INVISIBLE (-450 2675);
FORCEPROP 1 LAST PATH I182
J 0
(-375 2675);
DISPLAY 0.872340 (-375 2675);
PAINT AQUA (-375 2675);
DISPLAY INVISIBLE (-375 2675);
FORCEPROP 1 LAST SIZE 1B
J 0
(-375 2625);
DISPLAY 0.893617 (-375 2625);
PAINT GREEN (-375 2625);
DISPLAY INVISIBLE (-375 2625);
FORCEPROP 1 LAST HDL_POWER GND
J 0
(-450 2825);
DISPLAY 0.893617 (-450 2825);
PAINT GREEN (-450 2825);
DISPLAY INVISIBLE (-450 2825);
FORCEADD CAP..1
(-450 3050);
FORCEPROP 1 LASTPIN (-450 2950) $PN 2
J 0
(-440 2930);
DISPLAY 0.617021 (-440 2930);
PAINT ORANGE (-440 2930);
FORCEPROP 1 LAST TOLERANCE 20%
J 0
(-400 3000);
DISPLAY 0.617021 (-400 3000);
PAINT SKYBLUE (-400 3000);
FORCEPROP 1 LAST MATERIAL X6S
J 0
(-400 2950);
DISPLAY 0.617021 (-400 2950);
PAINT SKYBLUE (-400 2950);
FORCEPROP 1 LAST PACK_TYPE 0603LF
J 0
(-400 2850);
DISPLAY 0.617021 (-400 2850);
PAINT SKYBLUE (-400 2850);
FORCEPROP 1 LAST PART_NUMBER E15431-001
J 0
(-400 2900);
DISPLAY 0.617021 (-400 2900);
PAINT BLUE (-400 2900);
FORCEPROP 1 LAST VOLTAGE 4V
J 0
(-400 3050);
DISPLAY 0.617021 (-400 3050);
PAINT SKYBLUE (-400 3050);
FORCEPROP 1 LASTPIN (-450 3150) $PN 1
J 0
(-440 3130);
DISPLAY 0.617021 (-440 3130);
PAINT ORANGE (-440 3130);
FORCEPROP 1 LAST VALUE 10UF
J 0
(-400 3100);
DISPLAY 0.617021 (-400 3100);
PAINT SKYBLUE (-400 3100);
FORCEPROP 1 LAST LOCATION C2D42
J 0
(-400 3150);
DISPLAY 0.617021 (-400 3150);
PAINT AQUA (-400 3150);
FORCEPROP 2 LAST CDS_LIB mstr_discrete
J 0
(-450 3050);
PAINT ORANGE (-450 3050);
DISPLAY INVISIBLE (-450 3050);
FORCEPROP 2 LAST ROOM VDDQ_GHJ_CPU1
J 0
(-400 3200);
PAINT MONO (-400 3200);
DISPLAY INVISIBLE (-400 3200);
FORCEPROP 1 LAST PATH I183
J 0
(-400 3200);
DISPLAY 0.978723 (-400 3200);
PAINT WHITE (-400 3200);
DISPLAY INVISIBLE (-400 3200);
FORCEPROP 2 LAST CDS_LOCATION C2D42
J 0
(-400 3150);
DISPLAY 0.617021 (-400 3150);
PAINT AQUA (-400 3150);
DISPLAY INVISIBLE (-400 3150);
FORCEPROP 2 LAST SEC 1
J 0
(-400 3250);
DISPLAY 0.680851 (-400 3250);
PAINT MONO (-400 3250);
DISPLAY INVISIBLE (-400 3250);
FORCEPROP 2 LAST BOM_COST MEM_VRD_PVDDQ_GHJ
J 0
(-400 3200);
PAINT MONO (-400 3200);
DISPLAY INVISIBLE (-400 3200);
FORCEPROP 2 LAST SEC_TYPE 0603LF
J 0
(-400 3250);
DISPLAY 1.021277 (-400 3250);
PAINT ORANGE (-400 3250);
DISPLAY INVISIBLE (-400 3250);
FORCEADD CAP..1
(-2300 3050);
FORCEPROP 1 LAST PACK_TYPE 0805LF
J 0
(-2250 2850);
DISPLAY 0.617021 (-2250 2850);
PAINT SKYBLUE (-2250 2850);
FORCEPROP 1 LAST TOLERANCE 20%
J 0
(-2250 3000);
DISPLAY 0.617021 (-2250 3000);
PAINT SKYBLUE (-2250 3000);
FORCEPROP 1 LAST MATERIAL X6S
J 0
(-2250 2950);
DISPLAY 0.617021 (-2250 2950);
PAINT SKYBLUE (-2250 2950);
FORCEPROP 1 LASTPIN (-2300 2950) $PN 2
J 0
(-2290 2930);
DISPLAY 0.617021 (-2290 2930);
PAINT ORANGE (-2290 2930);
FORCEPROP 1 LASTPIN (-2300 3150) $PN 1
J 0
(-2290 3130);
DISPLAY 0.617021 (-2290 3130);
PAINT ORANGE (-2290 3130);
FORCEPROP 1 LAST LOCATION C8P30
J 0
(-2250 3150);
DISPLAY 0.617021 (-2250 3150);
PAINT AQUA (-2250 3150);
FORCEPROP 1 LAST VALUE 22UF
J 0
(-2250 3100);
DISPLAY 0.617021 (-2250 3100);
PAINT SKYBLUE (-2250 3100);
FORCEPROP 1 LAST PART_NUMBER C95333-002
J 0
(-2250 2900);
DISPLAY 0.617021 (-2250 2900);
PAINT BLUE (-2250 2900);
FORCEPROP 1 LAST VOLTAGE 4V
J 0
(-2250 3050);
PAINT SKYBLUE (-2250 3050);
DISPLAY INVISIBLE (-2250 3050);
FORCEPROP 2 LAST CDS_LIB mstr_discrete
J 0
(-2300 3050);
PAINT ORANGE (-2300 3050);
DISPLAY INVISIBLE (-2300 3050);
FORCEPROP 2 LAST CDS_LOCATION C8P30
J 0
(-2250 3150);
DISPLAY 0.617021 (-2250 3150);
PAINT AQUA (-2250 3150);
DISPLAY INVISIBLE (-2250 3150);
FORCEPROP 2 LAST BOM_COST MEM_VRD_PVDDQ_GHJ
J 0
(-2250 3200);
PAINT MONO (-2250 3200);
DISPLAY INVISIBLE (-2250 3200);
FORCEPROP 1 LAST PATH I184
J 0
(-2250 3200);
DISPLAY 0.978723 (-2250 3200);
PAINT WHITE (-2250 3200);
DISPLAY INVISIBLE (-2250 3200);
FORCEPROP 2 LAST ROOM VDDQ_GHJ_CPU1
J 0
(-2250 3200);
PAINT MONO (-2250 3200);
DISPLAY INVISIBLE (-2250 3200);
FORCEPROP 2 LAST SEC_TYPE 0805LF
J 0
(-2250 3250);
DISPLAY 1.021277 (-2250 3250);
PAINT ORANGE (-2250 3250);
DISPLAY INVISIBLE (-2250 3250);
FORCEPROP 2 LAST SEC 1
J 0
(-2250 3250);
DISPLAY 0.680851 (-2250 3250);
PAINT MONO (-2250 3250);
DISPLAY INVISIBLE (-2250 3250);
FORCEADD PVDDQ_GHJ..1
(-2300 3325);
FORCEPROP 3 LASTPIN (-2300 3275) SIG_NAME PVDDQ_GHJ\g
J 0
(-2290 3285);
DISPLAY 0.659574 (-2290 3285);
PAINT MONO (-2290 3285);
DISPLAY INVISIBLE (-2290 3285);
FORCEPROP 1 LAST BODY_TYPE PLUMBING
J 0
(-2345 3282);
DISPLAY 0.340426 (-2345 3282);
PAINT GREEN (-2345 3282);
DISPLAY INVISIBLE (-2345 3282);
FORCEPROP 1 LAST VOLTAGE 1.2V
J 0
(-2345 3282);
DISPLAY 0.340426 (-2345 3282);
PAINT SKYBLUE (-2345 3282);
DISPLAY INVISIBLE (-2345 3282);
FORCEPROP 2 LAST CDS_LIB mstr_symbols
J 0
(-2300 3325);
PAINT ORANGE (-2300 3325);
DISPLAY INVISIBLE (-2300 3325);
FORCEPROP 2 LAST ROOM VDDQ_GHJ_PWR_VR
J 0
(-2075 3425);
PAINT ORANGE (-2075 3425);
DISPLAY INVISIBLE (-2075 3425);
FORCEPROP 1 LAST PATH I185
J 0
(-2250 3350);
DISPLAY 0.872340 (-2250 3350);
PAINT AQUA (-2250 3350);
DISPLAY INVISIBLE (-2250 3350);
FORCEPROP 1 LAST HDL_POWER PVDDQ_GHJ
J 1
(-2300 3375);
DISPLAY 0.872340 (-2300 3375);
PAINT GREEN (-2300 3375);
DISPLAY INVISIBLE (-2300 3375);
FORCEPROP 2 LAST BOM_COST MEM_VRD_PVPP_AB
J 0
(-2250 3425);
PAINT MONO (-2250 3425);
DISPLAY INVISIBLE (-2250 3425);
FORCEADD PVDDQ_GHJ..1
(2600 1250);
FORCEPROP 3 LASTPIN (2600 1200) SIG_NAME PVDDQ_GHJ\g
J 0
(2610 1210);
DISPLAY 0.659574 (2610 1210);
PAINT MONO (2610 1210);
DISPLAY INVISIBLE (2610 1210);
FORCEPROP 1 LAST BODY_TYPE PLUMBING
J 0
(2555 1207);
DISPLAY 0.340426 (2555 1207);
PAINT GREEN (2555 1207);
DISPLAY INVISIBLE (2555 1207);
FORCEPROP 1 LAST VOLTAGE 1.2V
J 0
(2555 1207);
DISPLAY 0.340426 (2555 1207);
PAINT SKYBLUE (2555 1207);
DISPLAY INVISIBLE (2555 1207);
FORCEPROP 2 LAST CDS_LIB mstr_symbols
J 0
(2600 1250);
PAINT ORANGE (2600 1250);
DISPLAY INVISIBLE (2600 1250);
FORCEPROP 1 LAST PATH I189
J 0
(2650 1275);
DISPLAY 0.872340 (2650 1275);
PAINT AQUA (2650 1275);
DISPLAY INVISIBLE (2650 1275);
FORCEPROP 2 LAST BOM_COST MEM_VRD_PVDDQ_CD
J 0
(2675 1350);
PAINT MONO (2675 1350);
DISPLAY INVISIBLE (2675 1350);
FORCEPROP 1 LAST HDL_POWER PVDDQ_GHJ
J 1
(2600 1300);
DISPLAY 0.872340 (2600 1300);
PAINT GREEN (2600 1300);
DISPLAY INVISIBLE (2600 1300);
FORCEPROP 2 LAST ROOM VDDQ_GHJ_PWR_VR
J 0
(2850 1350);
PAINT ORANGE (2850 1350);
DISPLAY INVISIBLE (2850 1350);
FORCEADD GND..1
(3425 575);
FORCEPROP 3 LASTPIN (3425 625) SIG_NAME GND\g
J 0
(3435 635);
DISPLAY 0.659574 (3435 635);
PAINT MONO (3435 635);
DISPLAY INVISIBLE (3435 635);
FORCEPROP 2 LAST ROOM VDDQ_GHJ_PWR_VR
J 0
(2875 650);
PAINT ORANGE (2875 650);
DISPLAY INVISIBLE (2875 650);
FORCEPROP 2 LAST BOM_COST MEM_VRD_PVDDQ_CD
J 0
(3100 650);
PAINT MONO (3100 650);
DISPLAY INVISIBLE (3100 650);
FORCEPROP 1 LAST VOLTAGE 0
J 0
(3425 575);
PAINT SKYBLUE (3425 575);
DISPLAY INVISIBLE (3425 575);
FORCEPROP 2 LAST CDS_LIB mstr_symbols
J 0
(3425 575);
PAINT ORANGE (3425 575);
DISPLAY INVISIBLE (3425 575);
FORCEPROP 1 LAST BODY_TYPE PLUMBING
J 0
(3380 532);
DISPLAY 0.340426 (3380 532);
PAINT GREEN (3380 532);
DISPLAY INVISIBLE (3380 532);
FORCEPROP 1 LAST HDL_POWER GND
J 0
(3425 725);
DISPLAY 0.893617 (3425 725);
PAINT GREEN (3425 725);
DISPLAY INVISIBLE (3425 725);
FORCEPROP 1 LAST PATH I191
J 0
(3500 575);
DISPLAY 0.872340 (3500 575);
PAINT AQUA (3500 575);
DISPLAY INVISIBLE (3500 575);
FORCEPROP 1 LAST SIZE 1B
J 0
(3500 525);
DISPLAY 0.893617 (3500 525);
PAINT GREEN (3500 525);
DISPLAY INVISIBLE (3500 525);
FORCEADD CAP..1
(-1250 1175);
FORCEPROP 1 LAST PACK_TYPE 1210
J 0
(-1200 975);
DISPLAY 0.617021 (-1200 975);
PAINT SKYBLUE (-1200 975);
FORCEPROP 1 LAST VALUE 47UF
J 0
(-1200 1225);
DISPLAY 0.617021 (-1200 1225);
PAINT SKYBLUE (-1200 1225);
FORCEPROP 1 LAST TOLERANCE 20%
J 0
(-1200 1125);
DISPLAY 0.617021 (-1200 1125);
PAINT SKYBLUE (-1200 1125);
FORCEPROP 1 LAST VOLTAGE 16V
J 0
(-1200 1175);
DISPLAY 0.617021 (-1200 1175);
PAINT SKYBLUE (-1200 1175);
FORCEPROP 1 LAST MATERIAL X6S
J 0
(-1200 1075);
DISPLAY 0.617021 (-1200 1075);
PAINT SKYBLUE (-1200 1075);
FORCEPROP 1 LASTPIN (-1250 1075) $PN 2
J 0
(-1240 1055);
DISPLAY 0.617021 (-1240 1055);
PAINT ORANGE (-1240 1055);
FORCEPROP 1 LASTPIN (-1250 1275) $PN 1
J 0
(-1240 1255);
DISPLAY 0.617021 (-1240 1255);
PAINT ORANGE (-1240 1255);
FORCEPROP 1 LAST LOCATION C1G15
J 0
(-1200 1275);
DISPLAY 0.617021 (-1200 1275);
PAINT AQUA (-1200 1275);
FORCEPROP 1 LAST PART_NUMBER D38464-007
J 0
(-1200 1025);
DISPLAY 0.617021 (-1200 1025);
PAINT BLUE (-1200 1025);
FORCEPROP 2 LAST CDS_LIB mstr_discrete
J 0
(-1250 1175);
PAINT ORANGE (-1250 1175);
DISPLAY INVISIBLE (-1250 1175);
FORCEPROP 2 LAST CDS_LOCATION C1G15
J 0
(-1200 1275);
DISPLAY 0.617021 (-1200 1275);
PAINT AQUA (-1200 1275);
DISPLAY INVISIBLE (-1200 1275);
FORCEPROP 1 LAST PATH I192
J 0
(-1200 1325);
DISPLAY 0.978723 (-1200 1325);
PAINT WHITE (-1200 1325);
DISPLAY INVISIBLE (-1200 1325);
FORCEPROP 2 LAST SEC_TYPE 1210
J 0
(-1200 1375);
DISPLAY 1.021277 (-1200 1375);
PAINT ORANGE (-1200 1375);
DISPLAY INVISIBLE (-1200 1375);
FORCEPROP 2 LAST SEC 1
J 0
(-1200 1375);
PAINT MONO (-1200 1375);
DISPLAY INVISIBLE (-1200 1375);
FORCEADD CAP..1
(-800 1175);
FORCEPROP 1 LAST PACK_TYPE 1210
J 0
(-750 975);
DISPLAY 0.617021 (-750 975);
PAINT SKYBLUE (-750 975);
FORCEPROP 1 LASTPIN (-800 1275) $PN 1
J 0
(-790 1255);
DISPLAY 0.617021 (-790 1255);
PAINT ORANGE (-790 1255);
FORCEPROP 1 LASTPIN (-800 1075) $PN 2
J 0
(-790 1055);
DISPLAY 0.617021 (-790 1055);
PAINT ORANGE (-790 1055);
FORCEPROP 1 LAST MATERIAL X6S
J 0
(-750 1075);
DISPLAY 0.617021 (-750 1075);
PAINT SKYBLUE (-750 1075);
FORCEPROP 1 LAST VOLTAGE 16V
J 0
(-750 1175);
DISPLAY 0.617021 (-750 1175);
PAINT SKYBLUE (-750 1175);
FORCEPROP 1 LAST TOLERANCE 20%
J 0
(-750 1125);
DISPLAY 0.617021 (-750 1125);
PAINT SKYBLUE (-750 1125);
FORCEPROP 1 LAST VALUE 47UF
J 0
(-750 1225);
DISPLAY 0.617021 (-750 1225);
PAINT SKYBLUE (-750 1225);
FORCEPROP 1 LAST PART_NUMBER D38464-007
J 0
(-750 1025);
DISPLAY 0.617021 (-750 1025);
PAINT BLUE (-750 1025);
FORCEPROP 1 LAST LOCATION C1G12
J 0
(-750 1275);
DISPLAY 0.617021 (-750 1275);
PAINT AQUA (-750 1275);
FORCEPROP 2 LAST CDS_LIB mstr_discrete
J 0
(-800 1175);
PAINT ORANGE (-800 1175);
DISPLAY INVISIBLE (-800 1175);
FORCEPROP 2 LAST SEC_TYPE 1210
J 0
(-750 1375);
DISPLAY 1.021277 (-750 1375);
PAINT ORANGE (-750 1375);
DISPLAY INVISIBLE (-750 1375);
FORCEPROP 2 LAST SEC 1
J 0
(-750 1375);
PAINT MONO (-750 1375);
DISPLAY INVISIBLE (-750 1375);
FORCEPROP 2 LAST CDS_LOCATION C1G12
J 0
(-750 1275);
DISPLAY 0.617021 (-750 1275);
PAINT AQUA (-750 1275);
DISPLAY INVISIBLE (-750 1275);
FORCEPROP 1 LAST PATH I193
J 0
(-750 1325);
DISPLAY 0.978723 (-750 1325);
PAINT WHITE (-750 1325);
DISPLAY INVISIBLE (-750 1325);
FORCEADD CAP..1
(-375 1175);
FORCEPROP 1 LAST PACK_TYPE 1210
J 0
(-325 975);
DISPLAY 0.617021 (-325 975);
PAINT SKYBLUE (-325 975);
FORCEPROP 1 LASTPIN (-375 1075) $PN 2
J 0
(-365 1055);
DISPLAY 0.617021 (-365 1055);
PAINT ORANGE (-365 1055);
FORCEPROP 1 LASTPIN (-375 1275) $PN 1
J 0
(-365 1255);
DISPLAY 0.617021 (-365 1255);
PAINT ORANGE (-365 1255);
FORCEPROP 1 LAST MATERIAL X6S
J 0
(-325 1075);
DISPLAY 0.617021 (-325 1075);
PAINT SKYBLUE (-325 1075);
FORCEPROP 1 LAST VOLTAGE 16V
J 0
(-325 1175);
DISPLAY 0.617021 (-325 1175);
PAINT SKYBLUE (-325 1175);
FORCEPROP 1 LAST TOLERANCE 20%
J 0
(-325 1125);
DISPLAY 0.617021 (-325 1125);
PAINT SKYBLUE (-325 1125);
FORCEPROP 1 LAST VALUE 47UF
J 0
(-325 1225);
DISPLAY 0.617021 (-325 1225);
PAINT SKYBLUE (-325 1225);
FORCEPROP 1 LAST PART_NUMBER D38464-007
J 0
(-325 1025);
DISPLAY 0.617021 (-325 1025);
PAINT BLUE (-325 1025);
FORCEPROP 1 LAST LOCATION C1G2
J 0
(-325 1275);
DISPLAY 0.617021 (-325 1275);
PAINT AQUA (-325 1275);
FORCEPROP 2 LAST CDS_LIB mstr_discrete
J 0
(-375 1175);
PAINT ORANGE (-375 1175);
DISPLAY INVISIBLE (-375 1175);
FORCEPROP 2 LAST CDS_LOCATION C1G2
J 0
(-325 1275);
DISPLAY 0.617021 (-325 1275);
PAINT AQUA (-325 1275);
DISPLAY INVISIBLE (-325 1275);
FORCEPROP 1 LAST PATH I194
J 0
(-325 1325);
DISPLAY 0.978723 (-325 1325);
PAINT WHITE (-325 1325);
DISPLAY INVISIBLE (-325 1325);
FORCEPROP 2 LAST SEC 1
J 0
(-325 1375);
PAINT MONO (-325 1375);
DISPLAY INVISIBLE (-325 1375);
FORCEPROP 2 LAST SEC_TYPE 1210
J 0
(-325 1375);
DISPLAY 1.021277 (-325 1375);
PAINT ORANGE (-325 1375);
DISPLAY INVISIBLE (-325 1375);
FORCEADD CAP..1
(50 1175);
FORCEPROP 1 LAST PACK_TYPE 1210
J 0
(100 975);
DISPLAY 0.617021 (100 975);
PAINT SKYBLUE (100 975);
FORCEPROP 1 LAST VALUE 47UF
J 0
(100 1225);
DISPLAY 0.617021 (100 1225);
PAINT SKYBLUE (100 1225);
FORCEPROP 1 LAST TOLERANCE 20%
J 0
(100 1125);
DISPLAY 0.617021 (100 1125);
PAINT SKYBLUE (100 1125);
FORCEPROP 1 LAST VOLTAGE 16V
J 0
(100 1175);
DISPLAY 0.617021 (100 1175);
PAINT SKYBLUE (100 1175);
FORCEPROP 1 LAST MATERIAL X6S
J 0
(100 1075);
DISPLAY 0.617021 (100 1075);
PAINT SKYBLUE (100 1075);
FORCEPROP 1 LASTPIN (50 1075) $PN 2
J 0
(60 1055);
DISPLAY 0.617021 (60 1055);
PAINT ORANGE (60 1055);
FORCEPROP 1 LAST LOCATION C1G7
J 0
(100 1275);
DISPLAY 0.617021 (100 1275);
PAINT AQUA (100 1275);
FORCEPROP 1 LASTPIN (50 1275) $PN 1
J 0
(60 1255);
DISPLAY 0.617021 (60 1255);
PAINT ORANGE (60 1255);
FORCEPROP 1 LAST PART_NUMBER D38464-007
J 0
(100 1025);
DISPLAY 0.617021 (100 1025);
PAINT BLUE (100 1025);
FORCEPROP 2 LAST CDS_LIB mstr_discrete
J 0
(50 1175);
PAINT ORANGE (50 1175);
DISPLAY INVISIBLE (50 1175);
FORCEPROP 2 LAST CDS_LOCATION C1G7
J 0
(100 1275);
DISPLAY 0.617021 (100 1275);
PAINT AQUA (100 1275);
DISPLAY INVISIBLE (100 1275);
FORCEPROP 2 LAST SEC_TYPE 1210
J 0
(100 1375);
DISPLAY 1.021277 (100 1375);
PAINT ORANGE (100 1375);
DISPLAY INVISIBLE (100 1375);
FORCEPROP 2 LAST SEC 1
J 0
(100 1375);
PAINT MONO (100 1375);
DISPLAY INVISIBLE (100 1375);
FORCEPROP 1 LAST PATH I195
J 0
(100 1325);
DISPLAY 0.978723 (100 1325);
PAINT WHITE (100 1325);
DISPLAY INVISIBLE (100 1325);
FORCEADD CAP_A..1
(2600 975);
FORCEPROP 1 LAST TOLERANCE 20%
J 0
(2650 925);
DISPLAY 0.617021 (2650 925);
PAINT SKYBLUE (2650 925);
FORCEPROP 1 LAST PACK_TYPE 0603V
J 0
(2650 775);
DISPLAY 0.617021 (2650 775);
PAINT SKYBLUE (2650 775);
FORCEPROP 1 LAST VOLTAGE 4V
J 0
(2650 975);
DISPLAY 0.617021 (2650 975);
PAINT SKYBLUE (2650 975);
FORCEPROP 1 LAST MATERIAL X5R
J 0
(2650 875);
DISPLAY 0.617021 (2650 875);
PAINT SKYBLUE (2650 875);
FORCEPROP 1 LASTPIN (2600 875) $PN 2
J 0
(2610 855);
DISPLAY 0.617021 (2610 855);
PAINT ORANGE (2610 855);
FORCEPROP 1 LAST PART_NUMBER 602433-106
J 0
(2650 825);
DISPLAY 0.617021 (2650 825);
PAINT BLUE (2650 825);
FORCEPROP 1 LASTPIN (2600 1075) $PN 1
J 0
(2610 1055);
DISPLAY 0.617021 (2610 1055);
PAINT ORANGE (2610 1055);
FORCEPROP 1 LAST LOCATION C8T4
J 0
(2650 1075);
DISPLAY 0.617021 (2650 1075);
PAINT AQUA (2650 1075);
FORCEPROP 1 LAST VALUE 47UF
J 0
(2650 1025);
DISPLAY 0.617021 (2650 1025);
PAINT SKYBLUE (2650 1025);
FORCEPROP 2 LAST CDS_LIB dev_discrete
J 0
(2600 975);
PAINT ORANGE (2600 975);
DISPLAY INVISIBLE (2600 975);
FORCEPROP 2 LAST CDS_LOCATION C8T4
J 0
(2650 1075);
DISPLAY 0.617021 (2650 1075);
PAINT AQUA (2650 1075);
DISPLAY INVISIBLE (2650 1075);
FORCEPROP 1 LAST PATH I196
J 0
(2650 1125);
DISPLAY 0.978723 (2650 1125);
PAINT WHITE (2650 1125);
DISPLAY INVISIBLE (2650 1125);
FORCEPROP 2 LAST CDS_SEC 1
J 0
(2650 1125);
PAINT ORANGE (2650 1125);
DISPLAY INVISIBLE (2650 1125);
FORCEPROP 2 LAST SEC 1
J 0
(2650 1175);
DISPLAY 0.680851 (2650 1175);
PAINT MONO (2650 1175);
DISPLAY INVISIBLE (2650 1175);
FORCEPROP 2 LAST SEC_TYPE 0603V
J 0
(2650 1175);
DISPLAY 1.021277 (2650 1175);
PAINT ORANGE (2650 1175);
DISPLAY INVISIBLE (2650 1175);
FORCEADD CAP_A..1
(2950 975);
FORCEPROP 1 LAST VOLTAGE 4V
J 0
(3000 975);
DISPLAY 0.617021 (3000 975);
PAINT SKYBLUE (3000 975);
FORCEPROP 1 LASTPIN (2950 875) $PN 2
J 0
(2960 855);
DISPLAY 0.617021 (2960 855);
PAINT ORANGE (2960 855);
FORCEPROP 1 LASTPIN (2950 1075) $PN 1
J 0
(2960 1055);
DISPLAY 0.617021 (2960 1055);
PAINT ORANGE (2960 1055);
FORCEPROP 1 LAST LOCATION C2G8
J 0
(3000 1075);
DISPLAY 0.617021 (3000 1075);
PAINT AQUA (3000 1075);
FORCEPROP 1 LAST PART_NUMBER 602433-106
J 0
(3000 825);
DISPLAY 0.617021 (3000 825);
PAINT BLUE (3000 825);
FORCEPROP 1 LAST VALUE 47UF
J 0
(3000 1025);
DISPLAY 0.617021 (3000 1025);
PAINT SKYBLUE (3000 1025);
FORCEPROP 1 LAST TOLERANCE 20%
J 0
(3000 925);
DISPLAY 0.617021 (3000 925);
PAINT SKYBLUE (3000 925);
FORCEPROP 1 LAST PACK_TYPE 0603V
J 0
(3000 775);
DISPLAY 0.617021 (3000 775);
PAINT SKYBLUE (3000 775);
FORCEPROP 1 LAST MATERIAL X5R
J 0
(3000 875);
DISPLAY 0.617021 (3000 875);
PAINT SKYBLUE (3000 875);
FORCEPROP 2 LAST CDS_LIB dev_discrete
J 0
(2950 975);
PAINT ORANGE (2950 975);
DISPLAY INVISIBLE (2950 975);
FORCEPROP 2 LAST CDS_LOCATION C2G8
J 0
(3000 1075);
DISPLAY 0.617021 (3000 1075);
PAINT AQUA (3000 1075);
DISPLAY INVISIBLE (3000 1075);
FORCEPROP 2 LAST CDS_SEC 1
J 0
(3000 1125);
PAINT ORANGE (3000 1125);
DISPLAY INVISIBLE (3000 1125);
FORCEPROP 2 LAST SEC_TYPE 0603V
J 0
(3000 1175);
DISPLAY 1.021277 (3000 1175);
PAINT ORANGE (3000 1175);
DISPLAY INVISIBLE (3000 1175);
FORCEPROP 2 LAST SEC 1
J 0
(3000 1175);
DISPLAY 0.680851 (3000 1175);
PAINT MONO (3000 1175);
DISPLAY INVISIBLE (3000 1175);
FORCEPROP 1 LAST PATH I197
J 0
(3000 1125);
DISPLAY 0.978723 (3000 1125);
PAINT WHITE (3000 1125);
DISPLAY INVISIBLE (3000 1125);
FORCEADD CAP_A..1
(3350 975);
FORCEPROP 1 LASTPIN (3350 875) $PN 2
J 0
(3360 855);
DISPLAY 0.617021 (3360 855);
PAINT ORANGE (3360 855);
FORCEPROP 1 LAST MATERIAL X5R
J 0
(3400 875);
DISPLAY 0.617021 (3400 875);
PAINT SKYBLUE (3400 875);
FORCEPROP 1 LAST TOLERANCE 20%
J 0
(3400 925);
DISPLAY 0.617021 (3400 925);
PAINT SKYBLUE (3400 925);
FORCEPROP 1 LAST PACK_TYPE 0603V
J 0
(3400 775);
DISPLAY 0.617021 (3400 775);
PAINT SKYBLUE (3400 775);
FORCEPROP 1 LAST VOLTAGE 4V
J 0
(3400 975);
DISPLAY 0.617021 (3400 975);
PAINT SKYBLUE (3400 975);
FORCEPROP 1 LAST PART_NUMBER 602433-106
J 0
(3400 825);
DISPLAY 0.617021 (3400 825);
PAINT BLUE (3400 825);
FORCEPROP 1 LASTPIN (3350 1075) $PN 1
J 0
(3360 1055);
DISPLAY 0.617021 (3360 1055);
PAINT ORANGE (3360 1055);
FORCEPROP 1 LAST VALUE 47UF
J 0
(3400 1025);
DISPLAY 0.617021 (3400 1025);
PAINT SKYBLUE (3400 1025);
FORCEPROP 1 LAST LOCATION C8T2
J 0
(3400 1075);
DISPLAY 0.617021 (3400 1075);
PAINT AQUA (3400 1075);
FORCEPROP 2 LAST CDS_LIB dev_discrete
J 0
(3350 975);
PAINT ORANGE (3350 975);
DISPLAY INVISIBLE (3350 975);
FORCEPROP 1 LAST PATH I198
J 0
(3400 1125);
DISPLAY 0.978723 (3400 1125);
PAINT WHITE (3400 1125);
DISPLAY INVISIBLE (3400 1125);
FORCEPROP 2 LAST SEC 1
J 0
(3400 1175);
DISPLAY 0.680851 (3400 1175);
PAINT MONO (3400 1175);
DISPLAY INVISIBLE (3400 1175);
FORCEPROP 2 LAST SEC_TYPE 0603V
J 0
(3400 1175);
DISPLAY 1.021277 (3400 1175);
PAINT ORANGE (3400 1175);
DISPLAY INVISIBLE (3400 1175);
FORCEPROP 2 LAST CDS_SEC 1
J 0
(3400 1125);
PAINT ORANGE (3400 1125);
DISPLAY INVISIBLE (3400 1125);
FORCEPROP 2 LAST CDS_LOCATION C8T2
J 0
(3400 1075);
DISPLAY 0.617021 (3400 1075);
PAINT AQUA (3400 1075);
DISPLAY INVISIBLE (3400 1075);
FORCEADD CAP_A..1
(2550 1725);
FORCEPROP 1 LASTPIN (2550 1825) $PN 1
J 0
(2560 1805);
DISPLAY 0.617021 (2560 1805);
PAINT ORANGE (2560 1805);
FORCEPROP 1 LASTPIN (2550 1625) $PN 2
J 0
(2560 1605);
DISPLAY 0.617021 (2560 1605);
PAINT ORANGE (2560 1605);
FORCEPROP 1 LAST PACK_TYPE 0603V
J 0
(2600 1525);
DISPLAY 0.617021 (2600 1525);
PAINT SKYBLUE (2600 1525);
FORCEPROP 1 LAST LOCATION C8U13
J 0
(2600 1825);
DISPLAY 0.617021 (2600 1825);
PAINT AQUA (2600 1825);
FORCEPROP 1 LAST VALUE 47UF
J 0
(2600 1775);
DISPLAY 0.617021 (2600 1775);
PAINT SKYBLUE (2600 1775);
FORCEPROP 1 LAST TOLERANCE 20%
J 0
(2600 1675);
DISPLAY 0.617021 (2600 1675);
PAINT SKYBLUE (2600 1675);
FORCEPROP 1 LAST VOLTAGE 4V
J 0
(2600 1725);
DISPLAY 0.617021 (2600 1725);
PAINT SKYBLUE (2600 1725);
FORCEPROP 1 LAST MATERIAL X5R
J 0
(2600 1625);
DISPLAY 0.617021 (2600 1625);
PAINT SKYBLUE (2600 1625);
FORCEPROP 1 LAST PART_NUMBER 602433-106
J 0
(2600 1575);
DISPLAY 0.617021 (2600 1575);
PAINT BLUE (2600 1575);
FORCEPROP 2 LAST CDS_LIB dev_discrete
J 0
(2550 1725);
PAINT ORANGE (2550 1725);
DISPLAY INVISIBLE (2550 1725);
FORCEPROP 2 LAST CDS_LOCATION C8U13
J 0
(2600 1825);
DISPLAY 0.617021 (2600 1825);
PAINT AQUA (2600 1825);
DISPLAY INVISIBLE (2600 1825);
FORCEPROP 2 LAST CDS_SEC 1
J 0
(2600 1875);
PAINT ORANGE (2600 1875);
DISPLAY INVISIBLE (2600 1875);
FORCEPROP 2 LAST SEC_TYPE 0603V
J 0
(2600 1925);
DISPLAY 1.021277 (2600 1925);
PAINT ORANGE (2600 1925);
DISPLAY INVISIBLE (2600 1925);
FORCEPROP 2 LAST SEC 1
J 0
(2600 1925);
DISPLAY 0.680851 (2600 1925);
PAINT MONO (2600 1925);
DISPLAY INVISIBLE (2600 1925);
FORCEPROP 1 LAST PATH I199
J 0
(2600 1875);
DISPLAY 0.978723 (2600 1875);
PAINT WHITE (2600 1875);
DISPLAY INVISIBLE (2600 1875);
FORCEADD CAP_A..1
(2900 1725);
FORCEPROP 1 LAST TOLERANCE 20%
J 0
(2950 1675);
DISPLAY 0.617021 (2950 1675);
PAINT SKYBLUE (2950 1675);
FORCEPROP 1 LAST VOLTAGE 4V
J 0
(2950 1725);
DISPLAY 0.617021 (2950 1725);
PAINT SKYBLUE (2950 1725);
FORCEPROP 1 LAST MATERIAL X5R
J 0
(2950 1625);
DISPLAY 0.617021 (2950 1625);
PAINT SKYBLUE (2950 1625);
FORCEPROP 1 LASTPIN (2900 1625) $PN 2
J 0
(2910 1605);
DISPLAY 0.617021 (2910 1605);
PAINT ORANGE (2910 1605);
FORCEPROP 1 LAST VALUE 47UF
J 0
(2950 1775);
DISPLAY 0.617021 (2950 1775);
PAINT SKYBLUE (2950 1775);
FORCEPROP 1 LASTPIN (2900 1825) $PN 1
J 0
(2910 1805);
DISPLAY 0.617021 (2910 1805);
PAINT ORANGE (2910 1805);
FORCEPROP 1 LAST LOCATION C2G15
J 0
(2950 1825);
DISPLAY 0.617021 (2950 1825);
PAINT AQUA (2950 1825);
FORCEPROP 1 LAST PART_NUMBER 602433-106
J 0
(2950 1575);
DISPLAY 0.617021 (2950 1575);
PAINT BLUE (2950 1575);
FORCEPROP 1 LAST PACK_TYPE 0603V
J 0
(2950 1525);
DISPLAY 0.617021 (2950 1525);
PAINT SKYBLUE (2950 1525);
FORCEPROP 2 LAST CDS_LIB dev_discrete
J 0
(2900 1725);
PAINT ORANGE (2900 1725);
DISPLAY INVISIBLE (2900 1725);
FORCEPROP 2 LAST CDS_LOCATION C2G15
J 0
(2950 1825);
DISPLAY 0.617021 (2950 1825);
PAINT AQUA (2950 1825);
DISPLAY INVISIBLE (2950 1825);
FORCEPROP 2 LAST CDS_SEC 1
J 0
(2950 1875);
PAINT ORANGE (2950 1875);
DISPLAY INVISIBLE (2950 1875);
FORCEPROP 2 LAST SEC_TYPE 0603V
J 0
(2950 1925);
DISPLAY 1.021277 (2950 1925);
PAINT ORANGE (2950 1925);
DISPLAY INVISIBLE (2950 1925);
FORCEPROP 2 LAST SEC 1
J 0
(2950 1925);
DISPLAY 0.680851 (2950 1925);
PAINT MONO (2950 1925);
DISPLAY INVISIBLE (2950 1925);
FORCEPROP 1 LAST PATH I200
J 0
(2950 1875);
DISPLAY 0.978723 (2950 1875);
PAINT WHITE (2950 1875);
DISPLAY INVISIBLE (2950 1875);
FORCEADD CAP_A..1
(3300 1725);
FORCEPROP 1 LAST PACK_TYPE 0603V
J 0
(3350 1525);
DISPLAY 0.617021 (3350 1525);
PAINT SKYBLUE (3350 1525);
FORCEPROP 1 LASTPIN (3300 1825) $PN 1
J 0
(3310 1805);
DISPLAY 0.617021 (3310 1805);
PAINT ORANGE (3310 1805);
FORCEPROP 1 LASTPIN (3300 1625) $PN 2
J 0
(3310 1605);
DISPLAY 0.617021 (3310 1605);
PAINT ORANGE (3310 1605);
FORCEPROP 1 LAST LOCATION C2F1
J 0
(3350 1825);
DISPLAY 0.617021 (3350 1825);
PAINT AQUA (3350 1825);
FORCEPROP 1 LAST VALUE 47UF
J 0
(3350 1775);
DISPLAY 0.617021 (3350 1775);
PAINT SKYBLUE (3350 1775);
FORCEPROP 1 LAST TOLERANCE 20%
J 0
(3350 1675);
DISPLAY 0.617021 (3350 1675);
PAINT SKYBLUE (3350 1675);
FORCEPROP 1 LAST VOLTAGE 4V
J 0
(3350 1725);
DISPLAY 0.617021 (3350 1725);
PAINT SKYBLUE (3350 1725);
FORCEPROP 1 LAST MATERIAL X5R
J 0
(3350 1625);
DISPLAY 0.617021 (3350 1625);
PAINT SKYBLUE (3350 1625);
FORCEPROP 1 LAST PART_NUMBER 602433-106
J 0
(3350 1575);
DISPLAY 0.617021 (3350 1575);
PAINT BLUE (3350 1575);
FORCEPROP 2 LAST CDS_LIB dev_discrete
J 0
(3300 1725);
PAINT ORANGE (3300 1725);
DISPLAY INVISIBLE (3300 1725);
FORCEPROP 2 LAST CDS_LOCATION C2F1
J 0
(3350 1825);
DISPLAY 0.617021 (3350 1825);
PAINT AQUA (3350 1825);
DISPLAY INVISIBLE (3350 1825);
FORCEPROP 2 LAST CDS_SEC 1
J 0
(3350 1875);
PAINT ORANGE (3350 1875);
DISPLAY INVISIBLE (3350 1875);
FORCEPROP 2 LAST SEC_TYPE 0603V
J 0
(3350 1925);
DISPLAY 1.021277 (3350 1925);
PAINT ORANGE (3350 1925);
DISPLAY INVISIBLE (3350 1925);
FORCEPROP 2 LAST SEC 1
J 0
(3350 1925);
DISPLAY 0.680851 (3350 1925);
PAINT MONO (3350 1925);
DISPLAY INVISIBLE (3350 1925);
FORCEPROP 1 LAST PATH I201
J 0
(3350 1875);
DISPLAY 0.978723 (3350 1875);
PAINT WHITE (3350 1875);
DISPLAY INVISIBLE (3350 1875);
FORCEADD CAP_A..1
(3650 1725);
FORCEPROP 1 LAST PACK_TYPE 0603V
J 0
(3700 1525);
DISPLAY 0.617021 (3700 1525);
PAINT SKYBLUE (3700 1525);
FORCEPROP 1 LASTPIN (3650 1625) $PN 2
J 0
(3660 1605);
DISPLAY 0.617021 (3660 1605);
PAINT ORANGE (3660 1605);
FORCEPROP 1 LAST MATERIAL X5R
J 0
(3700 1625);
DISPLAY 0.617021 (3700 1625);
PAINT SKYBLUE (3700 1625);
FORCEPROP 1 LAST VOLTAGE 4V
J 0
(3700 1725);
DISPLAY 0.617021 (3700 1725);
PAINT SKYBLUE (3700 1725);
FORCEPROP 1 LAST TOLERANCE 20%
J 0
(3700 1675);
DISPLAY 0.617021 (3700 1675);
PAINT SKYBLUE (3700 1675);
FORCEPROP 1 LAST VALUE 47UF
J 0
(3700 1775);
DISPLAY 0.617021 (3700 1775);
PAINT SKYBLUE (3700 1775);
FORCEPROP 1 LASTPIN (3650 1825) $PN 1
J 0
(3660 1805);
DISPLAY 0.617021 (3660 1805);
PAINT ORANGE (3660 1805);
FORCEPROP 1 LAST LOCATION C8T1
J 0
(3700 1825);
DISPLAY 0.617021 (3700 1825);
PAINT AQUA (3700 1825);
FORCEPROP 1 LAST PART_NUMBER 602433-106
J 0
(3700 1575);
DISPLAY 0.617021 (3700 1575);
PAINT BLUE (3700 1575);
FORCEPROP 2 LAST CDS_LIB dev_discrete
J 0
(3650 1725);
PAINT ORANGE (3650 1725);
DISPLAY INVISIBLE (3650 1725);
FORCEPROP 1 LAST PATH I202
J 0
(3700 1875);
DISPLAY 0.978723 (3700 1875);
PAINT WHITE (3700 1875);
DISPLAY INVISIBLE (3700 1875);
FORCEPROP 2 LAST SEC 1
J 0
(3700 1925);
DISPLAY 0.680851 (3700 1925);
PAINT MONO (3700 1925);
DISPLAY INVISIBLE (3700 1925);
FORCEPROP 2 LAST SEC_TYPE 0603V
J 0
(3700 1925);
DISPLAY 1.021277 (3700 1925);
PAINT ORANGE (3700 1925);
DISPLAY INVISIBLE (3700 1925);
FORCEPROP 2 LAST CDS_SEC 1
J 0
(3700 1875);
PAINT ORANGE (3700 1875);
DISPLAY INVISIBLE (3700 1875);
FORCEPROP 2 LAST CDS_LOCATION C8T1
J 0
(3700 1825);
DISPLAY 0.617021 (3700 1825);
PAINT AQUA (3700 1825);
DISPLAY INVISIBLE (3700 1825);
FORCEADD CAP_A..1
(4000 1725);
FORCEPROP 1 LASTPIN (4000 1625) $PN 2
J 0
(4010 1605);
DISPLAY 0.617021 (4010 1605);
PAINT ORANGE (4010 1605);
FORCEPROP 1 LASTPIN (4000 1825) $PN 1
J 0
(4010 1805);
DISPLAY 0.617021 (4010 1805);
PAINT ORANGE (4010 1805);
FORCEPROP 1 LAST LOCATION C8U9
J 0
(4050 1825);
DISPLAY 0.617021 (4050 1825);
PAINT AQUA (4050 1825);
FORCEPROP 1 LAST PART_NUMBER 602433-106
J 0
(4050 1575);
DISPLAY 0.617021 (4050 1575);
PAINT BLUE (4050 1575);
FORCEPROP 1 LAST VALUE 47UF
J 0
(4050 1775);
DISPLAY 0.617021 (4050 1775);
PAINT SKYBLUE (4050 1775);
FORCEPROP 1 LAST TOLERANCE 20%
J 0
(4050 1675);
DISPLAY 0.617021 (4050 1675);
PAINT SKYBLUE (4050 1675);
FORCEPROP 1 LAST PACK_TYPE 0603V
J 0
(4050 1525);
DISPLAY 0.617021 (4050 1525);
PAINT SKYBLUE (4050 1525);
FORCEPROP 1 LAST VOLTAGE 4V
J 0
(4050 1725);
DISPLAY 0.617021 (4050 1725);
PAINT SKYBLUE (4050 1725);
FORCEPROP 1 LAST MATERIAL X5R
J 0
(4050 1625);
DISPLAY 0.617021 (4050 1625);
PAINT SKYBLUE (4050 1625);
FORCEPROP 2 LAST CDS_LIB dev_discrete
J 0
(4000 1725);
PAINT ORANGE (4000 1725);
DISPLAY INVISIBLE (4000 1725);
FORCEPROP 1 LAST PATH I203
J 0
(4050 1875);
DISPLAY 0.978723 (4050 1875);
PAINT WHITE (4050 1875);
DISPLAY INVISIBLE (4050 1875);
FORCEPROP 2 LAST SEC 1
J 0
(4050 1925);
DISPLAY 0.680851 (4050 1925);
PAINT MONO (4050 1925);
DISPLAY INVISIBLE (4050 1925);
FORCEPROP 2 LAST SEC_TYPE 0603V
J 0
(4050 1925);
DISPLAY 1.021277 (4050 1925);
PAINT ORANGE (4050 1925);
DISPLAY INVISIBLE (4050 1925);
FORCEPROP 2 LAST CDS_SEC 1
J 0
(4050 1875);
PAINT ORANGE (4050 1875);
DISPLAY INVISIBLE (4050 1875);
FORCEPROP 2 LAST CDS_LOCATION C8U9
J 0
(4050 1825);
DISPLAY 0.617021 (4050 1825);
PAINT AQUA (4050 1825);
DISPLAY INVISIBLE (4050 1825);
FORCEADD CAP_A..1
(4400 1725);
FORCEPROP 1 LAST PACK_TYPE 0603V
J 0
(4450 1525);
DISPLAY 0.617021 (4450 1525);
PAINT SKYBLUE (4450 1525);
FORCEPROP 1 LAST TOLERANCE 20%
J 0
(4450 1675);
DISPLAY 0.617021 (4450 1675);
PAINT SKYBLUE (4450 1675);
FORCEPROP 1 LAST VOLTAGE 4V
J 0
(4450 1725);
DISPLAY 0.617021 (4450 1725);
PAINT SKYBLUE (4450 1725);
FORCEPROP 1 LAST MATERIAL X5R
J 0
(4450 1625);
DISPLAY 0.617021 (4450 1625);
PAINT SKYBLUE (4450 1625);
FORCEPROP 1 LASTPIN (4400 1625) $PN 2
J 0
(4410 1605);
DISPLAY 0.617021 (4410 1605);
PAINT ORANGE (4410 1605);
FORCEPROP 1 LAST VALUE 47UF
J 0
(4450 1775);
DISPLAY 0.617021 (4450 1775);
PAINT SKYBLUE (4450 1775);
FORCEPROP 1 LAST LOCATION C8T11
J 0
(4450 1825);
DISPLAY 0.617021 (4450 1825);
PAINT AQUA (4450 1825);
FORCEPROP 1 LASTPIN (4400 1825) $PN 1
J 0
(4410 1805);
DISPLAY 0.617021 (4410 1805);
PAINT ORANGE (4410 1805);
FORCEPROP 1 LAST PART_NUMBER 602433-106
J 0
(4450 1575);
DISPLAY 0.617021 (4450 1575);
PAINT BLUE (4450 1575);
FORCEPROP 2 LAST CDS_LIB dev_discrete
J 0
(4400 1725);
PAINT ORANGE (4400 1725);
DISPLAY INVISIBLE (4400 1725);
FORCEPROP 2 LAST CDS_LOCATION C8T11
J 0
(4450 1825);
DISPLAY 0.617021 (4450 1825);
PAINT AQUA (4450 1825);
DISPLAY INVISIBLE (4450 1825);
FORCEPROP 2 LAST CDS_SEC 1
J 0
(4450 1875);
PAINT ORANGE (4450 1875);
DISPLAY INVISIBLE (4450 1875);
FORCEPROP 2 LAST SEC_TYPE 0603V
J 0
(4450 1925);
DISPLAY 1.021277 (4450 1925);
PAINT ORANGE (4450 1925);
DISPLAY INVISIBLE (4450 1925);
FORCEPROP 2 LAST SEC 1
J 0
(4450 1925);
DISPLAY 0.680851 (4450 1925);
PAINT MONO (4450 1925);
DISPLAY INVISIBLE (4450 1925);
FORCEPROP 1 LAST PATH I204
J 0
(4450 1875);
DISPLAY 0.978723 (4450 1875);
PAINT WHITE (4450 1875);
DISPLAY INVISIBLE (4450 1875);
FORCEADD PVDDQ_GHJ..1
(-1550 3325);
FORCEPROP 3 LASTPIN (-1550 3275) SIG_NAME PVDDQ_GHJ\g
J 0
(-1540 3285);
DISPLAY 0.659574 (-1540 3285);
PAINT MONO (-1540 3285);
DISPLAY INVISIBLE (-1540 3285);
FORCEPROP 1 LAST VOLTAGE 1.2V
J 0
(-1595 3282);
DISPLAY 0.340426 (-1595 3282);
PAINT SKYBLUE (-1595 3282);
DISPLAY INVISIBLE (-1595 3282);
FORCEPROP 1 LAST BODY_TYPE PLUMBING
J 0
(-1595 3282);
DISPLAY 0.340426 (-1595 3282);
PAINT GREEN (-1595 3282);
DISPLAY INVISIBLE (-1595 3282);
FORCEPROP 2 LAST CDS_LIB mstr_symbols
J 0
(-1550 3325);
PAINT ORANGE (-1550 3325);
DISPLAY INVISIBLE (-1550 3325);
FORCEPROP 1 LAST HDL_POWER PVDDQ_GHJ
J 1
(-1550 3375);
DISPLAY 0.872340 (-1550 3375);
PAINT GREEN (-1550 3375);
DISPLAY INVISIBLE (-1550 3375);
FORCEPROP 2 LAST ROOM VDDQ_GHJ_PWR_VR
J 0
(-1325 3425);
PAINT ORANGE (-1325 3425);
DISPLAY INVISIBLE (-1325 3425);
FORCEPROP 2 LAST BOM_COST MEM_VRD_PVPP_AB
J 0
(-1500 3425);
PAINT MONO (-1500 3425);
DISPLAY INVISIBLE (-1500 3425);
FORCEPROP 1 LAST PATH I205
J 0
(-1500 3350);
DISPLAY 0.872340 (-1500 3350);
PAINT AQUA (-1500 3350);
DISPLAY INVISIBLE (-1500 3350);
FORCEADD GND..1
(-1950 2700);
FORCEPROP 3 LASTPIN (-1950 2750) SIG_NAME GND\g
J 0
(-1940 2760);
DISPLAY 0.659574 (-1940 2760);
PAINT MONO (-1940 2760);
DISPLAY INVISIBLE (-1940 2760);
FORCEPROP 2 LAST BOM_COST MEM_VRD_PVDDQ_CD
J 0
(-2275 2775);
PAINT MONO (-2275 2775);
DISPLAY INVISIBLE (-2275 2775);
FORCEPROP 2 LAST ROOM VDDQ_ABC_PWR_VR
J 0
(-2500 2775);
PAINT ORANGE (-2500 2775);
DISPLAY INVISIBLE (-2500 2775);
FORCEPROP 1 LAST BODY_TYPE PLUMBING
J 0
(-1995 2657);
DISPLAY 0.340426 (-1995 2657);
PAINT GREEN (-1995 2657);
DISPLAY INVISIBLE (-1995 2657);
FORCEPROP 2 LAST CDS_LIB mstr_symbols
J 0
(-1950 2700);
PAINT ORANGE (-1950 2700);
DISPLAY INVISIBLE (-1950 2700);
FORCEPROP 1 LAST VOLTAGE 0
J 0
(-1950 2700);
PAINT SKYBLUE (-1950 2700);
DISPLAY INVISIBLE (-1950 2700);
FORCEPROP 1 LAST PATH I206
J 0
(-1875 2700);
DISPLAY 0.872340 (-1875 2700);
PAINT AQUA (-1875 2700);
DISPLAY INVISIBLE (-1875 2700);
FORCEPROP 1 LAST SIZE 1B
J 0
(-1875 2650);
DISPLAY 0.893617 (-1875 2650);
PAINT GREEN (-1875 2650);
DISPLAY INVISIBLE (-1875 2650);
FORCEPROP 1 LAST HDL_POWER GND
J 0
(-1950 2850);
DISPLAY 0.893617 (-1950 2850);
PAINT GREEN (-1950 2850);
DISPLAY INVISIBLE (-1950 2850);
FORCEADD CAP_A..1
(2100 250);
FORCEPROP 1 LASTPIN (2100 150) $PN 2
J 0
(2110 130);
DISPLAY 0.617021 (2110 130);
PAINT ORANGE (2110 130);
FORCEPROP 1 LAST MATERIAL X6S
J 0
(2150 150);
DISPLAY 0.617021 (2150 150);
PAINT SKYBLUE (2150 150);
FORCEPROP 1 LAST PACK_TYPE 0603V
J 0
(2150 50);
DISPLAY 0.617021 (2150 50);
PAINT SKYBLUE (2150 50);
FORCEPROP 1 LAST TOLERANCE 20%
J 0
(2150 200);
DISPLAY 0.617021 (2150 200);
PAINT SKYBLUE (2150 200);
FORCEPROP 1 LAST VOLTAGE 4V
J 0
(2150 250);
DISPLAY 0.617021 (2150 250);
PAINT SKYBLUE (2150 250);
FORCEPROP 1 LASTPIN (2100 350) $PN 1
J 0
(2110 330);
DISPLAY 0.617021 (2110 330);
PAINT ORANGE (2110 330);
FORCEPROP 1 LAST LOCATION C3G6
J 0
(2150 350);
DISPLAY 0.617021 (2150 350);
PAINT AQUA (2150 350);
FORCEPROP 1 LAST PART_NUMBER E15431-004
J 0
(2150 100);
DISPLAY 0.617021 (2150 100);
PAINT BLUE (2150 100);
FORCEPROP 1 LAST VALUE 22.0UF
J 0
(2150 300);
DISPLAY 0.617021 (2150 300);
PAINT SKYBLUE (2150 300);
FORCEPROP 2 LAST CDS_LIB dev_discrete
J 0
(2100 250);
PAINT ORANGE (2100 250);
DISPLAY INVISIBLE (2100 250);
FORCEPROP 2 LAST CDS_LOCATION C3G6
J 0
(2150 350);
DISPLAY 0.617021 (2150 350);
PAINT AQUA (2150 350);
DISPLAY INVISIBLE (2150 350);
FORCEPROP 0 LAST ROOM PVDDQ_GHJ
J 0
(2150 450);
DISPLAY 1.021277 (2150 450);
PAINT ORANGE (2150 450);
DISPLAY INVISIBLE (2150 450);
FORCEPROP 1 LAST PATH I207
J 0
(2150 400);
DISPLAY 0.978723 (2150 400);
PAINT WHITE (2150 400);
DISPLAY INVISIBLE (2150 400);
FORCEPROP 2 LAST SEC 1
J 0
(2150 450);
DISPLAY 0.680851 (2150 450);
PAINT MONO (2150 450);
DISPLAY INVISIBLE (2150 450);
FORCEPROP 2 LAST SEC_TYPE 0603V
J 0
(2150 450);
DISPLAY 1.021277 (2150 450);
PAINT ORANGE (2150 450);
DISPLAY INVISIBLE (2150 450);
FORCEPROP 2 LAST CDS_SEC 1
J 0
(2150 400);
PAINT ORANGE (2150 400);
DISPLAY INVISIBLE (2150 400);
FORCEADD CAP_A..1
(1825 250);
FORCEPROP 1 LASTPIN (1825 150) $PN 2
J 0
(1835 130);
DISPLAY 0.617021 (1835 130);
PAINT ORANGE (1835 130);
FORCEPROP 1 LAST MATERIAL X6S
J 0
(1875 150);
DISPLAY 0.617021 (1875 150);
PAINT SKYBLUE (1875 150);
FORCEPROP 1 LAST PACK_TYPE 0603V
J 0
(1875 50);
DISPLAY 0.617021 (1875 50);
PAINT SKYBLUE (1875 50);
FORCEPROP 1 LAST TOLERANCE 20%
J 0
(1875 200);
DISPLAY 0.617021 (1875 200);
PAINT SKYBLUE (1875 200);
FORCEPROP 1 LAST VOLTAGE 4V
J 0
(1875 250);
DISPLAY 0.617021 (1875 250);
PAINT SKYBLUE (1875 250);
FORCEPROP 1 LASTPIN (1825 350) $PN 1
J 0
(1835 330);
DISPLAY 0.617021 (1835 330);
PAINT ORANGE (1835 330);
FORCEPROP 1 LAST LOCATION C3G5
J 0
(1875 350);
DISPLAY 0.617021 (1875 350);
PAINT AQUA (1875 350);
FORCEPROP 1 LAST PART_NUMBER E15431-004
J 0
(1875 100);
DISPLAY 0.617021 (1875 100);
PAINT BLUE (1875 100);
FORCEPROP 1 LAST VALUE 22.0UF
J 0
(1875 300);
DISPLAY 0.617021 (1875 300);
PAINT SKYBLUE (1875 300);
FORCEPROP 2 LAST CDS_LIB dev_discrete
J 0
(1825 250);
PAINT ORANGE (1825 250);
DISPLAY INVISIBLE (1825 250);
FORCEPROP 2 LAST CDS_LOCATION C3G5
J 0
(1875 350);
DISPLAY 0.617021 (1875 350);
PAINT AQUA (1875 350);
DISPLAY INVISIBLE (1875 350);
FORCEPROP 2 LAST CDS_SEC 1
J 0
(1875 400);
PAINT ORANGE (1875 400);
DISPLAY INVISIBLE (1875 400);
FORCEPROP 2 LAST SEC_TYPE 0603V
J 0
(1875 450);
DISPLAY 1.021277 (1875 450);
PAINT ORANGE (1875 450);
DISPLAY INVISIBLE (1875 450);
FORCEPROP 2 LAST SEC 1
J 0
(1875 450);
DISPLAY 0.680851 (1875 450);
PAINT MONO (1875 450);
DISPLAY INVISIBLE (1875 450);
FORCEPROP 1 LAST PATH I208
J 0
(1875 400);
DISPLAY 0.978723 (1875 400);
PAINT WHITE (1875 400);
DISPLAY INVISIBLE (1875 400);
FORCEPROP 0 LAST ROOM PVDDQ_GHJ
J 0
(1875 450);
DISPLAY 1.021277 (1875 450);
PAINT ORANGE (1875 450);
DISPLAY INVISIBLE (1875 450);
FORCEADD CAP_A..1
(1525 250);
FORCEPROP 1 LASTPIN (1525 350) $PN 1
J 0
(1535 330);
DISPLAY 0.617021 (1535 330);
PAINT ORANGE (1535 330);
FORCEPROP 1 LASTPIN (1525 150) $PN 2
J 0
(1535 130);
DISPLAY 0.617021 (1535 130);
PAINT ORANGE (1535 130);
FORCEPROP 1 LAST LOCATION C2G14
J 0
(1575 350);
DISPLAY 0.617021 (1575 350);
PAINT AQUA (1575 350);
FORCEPROP 1 LAST VALUE 22.0UF
J 0
(1575 300);
DISPLAY 0.617021 (1575 300);
PAINT SKYBLUE (1575 300);
FORCEPROP 1 LAST TOLERANCE 20%
J 0
(1575 200);
DISPLAY 0.617021 (1575 200);
PAINT SKYBLUE (1575 200);
FORCEPROP 1 LAST PACK_TYPE 0603V
J 0
(1575 50);
DISPLAY 0.617021 (1575 50);
PAINT SKYBLUE (1575 50);
FORCEPROP 1 LAST VOLTAGE 4V
J 0
(1575 250);
DISPLAY 0.617021 (1575 250);
PAINT SKYBLUE (1575 250);
FORCEPROP 1 LAST MATERIAL X6S
J 0
(1575 150);
DISPLAY 0.617021 (1575 150);
PAINT SKYBLUE (1575 150);
FORCEPROP 1 LAST PART_NUMBER E15431-004
J 0
(1575 100);
DISPLAY 0.617021 (1575 100);
PAINT BLUE (1575 100);
FORCEPROP 2 LAST CDS_LIB dev_discrete
J 0
(1525 250);
PAINT ORANGE (1525 250);
DISPLAY INVISIBLE (1525 250);
FORCEPROP 2 LAST CDS_LOCATION C2G14
J 0
(1575 350);
DISPLAY 0.617021 (1575 350);
PAINT AQUA (1575 350);
DISPLAY INVISIBLE (1575 350);
FORCEPROP 2 LAST CDS_SEC 1
J 0
(1575 400);
PAINT ORANGE (1575 400);
DISPLAY INVISIBLE (1575 400);
FORCEPROP 2 LAST SEC_TYPE 0603V
J 0
(1575 450);
DISPLAY 1.021277 (1575 450);
PAINT ORANGE (1575 450);
DISPLAY INVISIBLE (1575 450);
FORCEPROP 2 LAST SEC 1
J 0
(1575 450);
DISPLAY 0.680851 (1575 450);
PAINT MONO (1575 450);
DISPLAY INVISIBLE (1575 450);
FORCEPROP 1 LAST PATH I209
J 0
(1575 400);
DISPLAY 0.978723 (1575 400);
PAINT WHITE (1575 400);
DISPLAY INVISIBLE (1575 400);
FORCEPROP 0 LAST ROOM PVDDQ_GHJ
J 0
(1575 450);
DISPLAY 1.021277 (1575 450);
PAINT ORANGE (1575 450);
DISPLAY INVISIBLE (1575 450);
FORCEADD CAP_A..1
(1225 250);
FORCEPROP 1 LASTPIN (1225 150) $PN 2
J 0
(1235 130);
DISPLAY 0.617021 (1235 130);
PAINT ORANGE (1235 130);
FORCEPROP 1 LASTPIN (1225 350) $PN 1
J 0
(1235 330);
DISPLAY 0.617021 (1235 330);
PAINT ORANGE (1235 330);
FORCEPROP 1 LAST LOCATION C2G13
J 0
(1275 350);
DISPLAY 0.617021 (1275 350);
PAINT AQUA (1275 350);
FORCEPROP 1 LAST VALUE 22.0UF
J 0
(1275 300);
DISPLAY 0.617021 (1275 300);
PAINT SKYBLUE (1275 300);
FORCEPROP 1 LAST TOLERANCE 20%
J 0
(1275 200);
DISPLAY 0.617021 (1275 200);
PAINT SKYBLUE (1275 200);
FORCEPROP 1 LAST PACK_TYPE 0603V
J 0
(1275 50);
DISPLAY 0.617021 (1275 50);
PAINT SKYBLUE (1275 50);
FORCEPROP 1 LAST VOLTAGE 4V
J 0
(1275 250);
DISPLAY 0.617021 (1275 250);
PAINT SKYBLUE (1275 250);
FORCEPROP 1 LAST MATERIAL X6S
J 0
(1275 150);
DISPLAY 0.617021 (1275 150);
PAINT SKYBLUE (1275 150);
FORCEPROP 1 LAST PART_NUMBER E15431-004
J 0
(1275 100);
DISPLAY 0.617021 (1275 100);
PAINT BLUE (1275 100);
FORCEPROP 2 LAST CDS_LIB dev_discrete
J 0
(1225 250);
PAINT ORANGE (1225 250);
DISPLAY INVISIBLE (1225 250);
FORCEPROP 2 LAST CDS_LOCATION C2G13
J 0
(1275 350);
DISPLAY 0.617021 (1275 350);
PAINT AQUA (1275 350);
DISPLAY INVISIBLE (1275 350);
FORCEPROP 1 LAST PATH I210
J 0
(1275 400);
DISPLAY 0.978723 (1275 400);
PAINT WHITE (1275 400);
DISPLAY INVISIBLE (1275 400);
FORCEPROP 2 LAST SEC 1
J 0
(1275 450);
DISPLAY 0.680851 (1275 450);
PAINT MONO (1275 450);
DISPLAY INVISIBLE (1275 450);
FORCEPROP 2 LAST SEC_TYPE 0603V
J 0
(1275 450);
DISPLAY 1.021277 (1275 450);
PAINT ORANGE (1275 450);
DISPLAY INVISIBLE (1275 450);
FORCEPROP 2 LAST CDS_SEC 1
J 0
(1275 400);
PAINT ORANGE (1275 400);
DISPLAY INVISIBLE (1275 400);
FORCEPROP 0 LAST ROOM PVDDQ_GHJ
J 0
(1275 450);
DISPLAY 1.021277 (1275 450);
PAINT ORANGE (1275 450);
DISPLAY INVISIBLE (1275 450);
FORCEADD CAP_A..1
(950 250);
FORCEPROP 1 LASTPIN (950 150) $PN 2
J 0
(960 130);
DISPLAY 0.617021 (960 130);
PAINT ORANGE (960 130);
FORCEPROP 1 LASTPIN (950 350) $PN 1
J 0
(960 330);
DISPLAY 0.617021 (960 330);
PAINT ORANGE (960 330);
FORCEPROP 1 LAST LOCATION C3G2
J 0
(1000 350);
DISPLAY 0.617021 (1000 350);
PAINT AQUA (1000 350);
FORCEPROP 1 LAST PART_NUMBER E15431-004
J 0
(1000 100);
DISPLAY 0.617021 (1000 100);
PAINT BLUE (1000 100);
FORCEPROP 1 LAST VALUE 22.0UF
J 0
(1000 300);
DISPLAY 0.617021 (1000 300);
PAINT SKYBLUE (1000 300);
FORCEPROP 1 LAST TOLERANCE 20%
J 0
(1000 200);
DISPLAY 0.617021 (1000 200);
PAINT SKYBLUE (1000 200);
FORCEPROP 1 LAST PACK_TYPE 0603V
J 0
(1000 50);
DISPLAY 0.617021 (1000 50);
PAINT SKYBLUE (1000 50);
FORCEPROP 1 LAST VOLTAGE 4V
J 0
(1000 250);
DISPLAY 0.617021 (1000 250);
PAINT SKYBLUE (1000 250);
FORCEPROP 1 LAST MATERIAL X6S
J 0
(1000 150);
DISPLAY 0.617021 (1000 150);
PAINT SKYBLUE (1000 150);
FORCEPROP 2 LAST CDS_LIB dev_discrete
J 0
(950 250);
PAINT ORANGE (950 250);
DISPLAY INVISIBLE (950 250);
FORCEPROP 2 LAST CDS_LOCATION C3G2
J 0
(1000 350);
DISPLAY 0.617021 (1000 350);
PAINT AQUA (1000 350);
DISPLAY INVISIBLE (1000 350);
FORCEPROP 1 LAST PATH I211
J 0
(1000 400);
DISPLAY 0.978723 (1000 400);
PAINT WHITE (1000 400);
DISPLAY INVISIBLE (1000 400);
FORCEPROP 2 LAST SEC 1
J 0
(1000 450);
DISPLAY 0.680851 (1000 450);
PAINT MONO (1000 450);
DISPLAY INVISIBLE (1000 450);
FORCEPROP 2 LAST SEC_TYPE 0603V
J 0
(1000 450);
DISPLAY 1.021277 (1000 450);
PAINT ORANGE (1000 450);
DISPLAY INVISIBLE (1000 450);
FORCEPROP 2 LAST CDS_SEC 1
J 0
(1000 400);
PAINT ORANGE (1000 400);
DISPLAY INVISIBLE (1000 400);
FORCEPROP 0 LAST ROOM PVDDQ_GHJ
J 0
(1000 450);
DISPLAY 1.021277 (1000 450);
PAINT ORANGE (1000 450);
DISPLAY INVISIBLE (1000 450);
FORCEADD CAP_A..1
(675 250);
FORCEPROP 1 LASTPIN (675 150) $PN 2
J 0
(685 130);
DISPLAY 0.617021 (685 130);
PAINT ORANGE (685 130);
FORCEPROP 1 LASTPIN (675 350) $PN 1
J 0
(685 330);
DISPLAY 0.617021 (685 330);
PAINT ORANGE (685 330);
FORCEPROP 1 LAST LOCATION C3G1
J 0
(725 350);
DISPLAY 0.617021 (725 350);
PAINT AQUA (725 350);
FORCEPROP 1 LAST PART_NUMBER E15431-004
J 0
(725 100);
DISPLAY 0.617021 (725 100);
PAINT BLUE (725 100);
FORCEPROP 1 LAST VALUE 22.0UF
J 0
(725 300);
DISPLAY 0.617021 (725 300);
PAINT SKYBLUE (725 300);
FORCEPROP 1 LAST TOLERANCE 20%
J 0
(725 200);
DISPLAY 0.617021 (725 200);
PAINT SKYBLUE (725 200);
FORCEPROP 1 LAST PACK_TYPE 0603V
J 0
(725 50);
DISPLAY 0.617021 (725 50);
PAINT SKYBLUE (725 50);
FORCEPROP 1 LAST VOLTAGE 4V
J 0
(725 250);
DISPLAY 0.617021 (725 250);
PAINT SKYBLUE (725 250);
FORCEPROP 1 LAST MATERIAL X6S
J 0
(725 150);
DISPLAY 0.617021 (725 150);
PAINT SKYBLUE (725 150);
FORCEPROP 2 LAST CDS_LIB dev_discrete
J 0
(675 250);
PAINT ORANGE (675 250);
DISPLAY INVISIBLE (675 250);
FORCEPROP 2 LAST CDS_LOCATION C3G1
J 0
(725 350);
DISPLAY 0.617021 (725 350);
PAINT AQUA (725 350);
DISPLAY INVISIBLE (725 350);
FORCEPROP 1 LAST PATH I212
J 0
(725 400);
DISPLAY 0.978723 (725 400);
PAINT WHITE (725 400);
DISPLAY INVISIBLE (725 400);
FORCEPROP 2 LAST SEC 1
J 0
(725 450);
DISPLAY 0.680851 (725 450);
PAINT MONO (725 450);
DISPLAY INVISIBLE (725 450);
FORCEPROP 2 LAST SEC_TYPE 0603V
J 0
(725 450);
DISPLAY 1.021277 (725 450);
PAINT ORANGE (725 450);
DISPLAY INVISIBLE (725 450);
FORCEPROP 2 LAST CDS_SEC 1
J 0
(725 400);
PAINT ORANGE (725 400);
DISPLAY INVISIBLE (725 400);
FORCEPROP 0 LAST ROOM PVDDQ_GHJ
J 0
(725 450);
DISPLAY 1.021277 (725 450);
PAINT ORANGE (725 450);
DISPLAY INVISIBLE (725 450);
FORCEADD CAP_A..1
(375 250);
FORCEPROP 1 LASTPIN (375 150) $PN 2
J 0
(385 130);
DISPLAY 0.617021 (385 130);
PAINT ORANGE (385 130);
FORCEPROP 1 LAST VOLTAGE 4V
J 0
(425 250);
DISPLAY 0.617021 (425 250);
PAINT SKYBLUE (425 250);
FORCEPROP 1 LASTPIN (375 350) $PN 1
J 0
(385 330);
DISPLAY 0.617021 (385 330);
PAINT ORANGE (385 330);
FORCEPROP 1 LAST LOCATION C2G6
J 0
(425 350);
DISPLAY 0.617021 (425 350);
PAINT AQUA (425 350);
FORCEPROP 1 LAST PART_NUMBER E15431-004
J 0
(425 100);
DISPLAY 0.617021 (425 100);
PAINT BLUE (425 100);
FORCEPROP 1 LAST VALUE 22.0UF
J 0
(425 300);
DISPLAY 0.617021 (425 300);
PAINT SKYBLUE (425 300);
FORCEPROP 1 LAST TOLERANCE 20%
J 0
(425 200);
DISPLAY 0.617021 (425 200);
PAINT SKYBLUE (425 200);
FORCEPROP 1 LAST PACK_TYPE 0603V
J 0
(425 50);
DISPLAY 0.617021 (425 50);
PAINT SKYBLUE (425 50);
FORCEPROP 1 LAST MATERIAL X6S
J 0
(425 150);
DISPLAY 0.617021 (425 150);
PAINT SKYBLUE (425 150);
FORCEPROP 2 LAST CDS_LIB dev_discrete
J 0
(375 250);
PAINT ORANGE (375 250);
DISPLAY INVISIBLE (375 250);
FORCEPROP 2 LAST CDS_SEC 1
J 0
(425 400);
PAINT ORANGE (425 400);
DISPLAY INVISIBLE (425 400);
FORCEPROP 2 LAST CDS_LOCATION C2G6
J 0
(425 350);
DISPLAY 0.617021 (425 350);
PAINT AQUA (425 350);
DISPLAY INVISIBLE (425 350);
FORCEPROP 2 LAST SEC 1
J 0
(425 450);
DISPLAY 0.680851 (425 450);
PAINT MONO (425 450);
DISPLAY INVISIBLE (425 450);
FORCEPROP 2 LAST SEC_TYPE 0603V
J 0
(425 450);
DISPLAY 1.021277 (425 450);
PAINT ORANGE (425 450);
DISPLAY INVISIBLE (425 450);
FORCEPROP 0 LAST ROOM PVDDQ_GHJ
J 0
(425 450);
DISPLAY 1.021277 (425 450);
PAINT ORANGE (425 450);
DISPLAY INVISIBLE (425 450);
FORCEPROP 1 LAST PATH I213
J 0
(425 400);
DISPLAY 0.978723 (425 400);
PAINT WHITE (425 400);
DISPLAY INVISIBLE (425 400);
FORCEADD CAP_A..1
(75 250);
FORCEPROP 1 LASTPIN (75 150) $PN 2
J 0
(85 130);
DISPLAY 0.617021 (85 130);
PAINT ORANGE (85 130);
FORCEPROP 1 LAST MATERIAL X6S
J 0
(125 150);
DISPLAY 0.617021 (125 150);
PAINT SKYBLUE (125 150);
FORCEPROP 1 LAST TOLERANCE 20%
J 0
(125 200);
DISPLAY 0.617021 (125 200);
PAINT SKYBLUE (125 200);
FORCEPROP 1 LAST VOLTAGE 4V
J 0
(125 250);
DISPLAY 0.617021 (125 250);
PAINT SKYBLUE (125 250);
FORCEPROP 1 LASTPIN (75 350) $PN 1
J 0
(85 330);
DISPLAY 0.617021 (85 330);
PAINT ORANGE (85 330);
FORCEPROP 1 LAST LOCATION C2G5
J 0
(125 350);
DISPLAY 0.617021 (125 350);
PAINT AQUA (125 350);
FORCEPROP 1 LAST PART_NUMBER E15431-004
J 0
(125 100);
DISPLAY 0.617021 (125 100);
PAINT BLUE (125 100);
FORCEPROP 1 LAST VALUE 22.0UF
J 0
(125 300);
DISPLAY 0.617021 (125 300);
PAINT SKYBLUE (125 300);
FORCEPROP 1 LAST PACK_TYPE 0603V
J 0
(125 50);
DISPLAY 0.617021 (125 50);
PAINT SKYBLUE (125 50);
FORCEPROP 2 LAST CDS_LIB dev_discrete
J 0
(75 250);
PAINT ORANGE (75 250);
DISPLAY INVISIBLE (75 250);
FORCEPROP 2 LAST CDS_LOCATION C2G5
J 0
(125 350);
DISPLAY 0.617021 (125 350);
PAINT AQUA (125 350);
DISPLAY INVISIBLE (125 350);
FORCEPROP 2 LAST CDS_SEC 1
J 0
(125 400);
PAINT ORANGE (125 400);
DISPLAY INVISIBLE (125 400);
FORCEPROP 2 LAST SEC_TYPE 0603V
J 0
(125 450);
DISPLAY 1.021277 (125 450);
PAINT ORANGE (125 450);
DISPLAY INVISIBLE (125 450);
FORCEPROP 2 LAST SEC 1
J 0
(125 450);
DISPLAY 0.680851 (125 450);
PAINT MONO (125 450);
DISPLAY INVISIBLE (125 450);
FORCEPROP 1 LAST PATH I214
J 0
(125 400);
DISPLAY 0.978723 (125 400);
PAINT WHITE (125 400);
DISPLAY INVISIBLE (125 400);
FORCEPROP 0 LAST ROOM PVDDQ_GHJ
J 0
(125 450);
DISPLAY 1.021277 (125 450);
PAINT ORANGE (125 450);
DISPLAY INVISIBLE (125 450);
FORCEADD CAP_A..1
(-250 250);
FORCEPROP 1 LASTPIN (-250 150) $PN 2
J 0
(-240 130);
DISPLAY 0.617021 (-240 130);
PAINT ORANGE (-240 130);
FORCEPROP 1 LAST MATERIAL X6S
J 0
(-200 150);
DISPLAY 0.617021 (-200 150);
PAINT SKYBLUE (-200 150);
FORCEPROP 1 LAST PACK_TYPE 0603V
J 0
(-200 50);
DISPLAY 0.617021 (-200 50);
PAINT SKYBLUE (-200 50);
FORCEPROP 1 LAST TOLERANCE 20%
J 0
(-200 200);
DISPLAY 0.617021 (-200 200);
PAINT SKYBLUE (-200 200);
FORCEPROP 1 LAST VOLTAGE 4V
J 0
(-200 250);
DISPLAY 0.617021 (-200 250);
PAINT SKYBLUE (-200 250);
FORCEPROP 1 LASTPIN (-250 350) $PN 1
J 0
(-240 330);
DISPLAY 0.617021 (-240 330);
PAINT ORANGE (-240 330);
FORCEPROP 1 LAST LOCATION C2G4
J 0
(-200 350);
DISPLAY 0.617021 (-200 350);
PAINT AQUA (-200 350);
FORCEPROP 1 LAST VALUE 22.0UF
J 0
(-200 300);
DISPLAY 0.617021 (-200 300);
PAINT SKYBLUE (-200 300);
FORCEPROP 1 LAST PART_NUMBER E15431-004
J 0
(-200 100);
DISPLAY 0.617021 (-200 100);
PAINT BLUE (-200 100);
FORCEPROP 2 LAST CDS_LIB dev_discrete
J 0
(-250 250);
PAINT ORANGE (-250 250);
DISPLAY INVISIBLE (-250 250);
FORCEPROP 0 LAST ROOM PVDDQ_GHJ
J 0
(-200 450);
DISPLAY 1.021277 (-200 450);
PAINT ORANGE (-200 450);
DISPLAY INVISIBLE (-200 450);
FORCEPROP 1 LAST PATH I215
J 0
(-200 400);
DISPLAY 0.978723 (-200 400);
PAINT WHITE (-200 400);
DISPLAY INVISIBLE (-200 400);
FORCEPROP 2 LAST SEC 1
J 0
(-200 450);
DISPLAY 0.680851 (-200 450);
PAINT MONO (-200 450);
DISPLAY INVISIBLE (-200 450);
FORCEPROP 2 LAST SEC_TYPE 0603V
J 0
(-200 450);
DISPLAY 1.021277 (-200 450);
PAINT ORANGE (-200 450);
DISPLAY INVISIBLE (-200 450);
FORCEPROP 2 LAST CDS_SEC 1
J 0
(-200 400);
PAINT ORANGE (-200 400);
DISPLAY INVISIBLE (-200 400);
FORCEPROP 2 LAST CDS_LOCATION C2G4
J 0
(-200 350);
DISPLAY 0.617021 (-200 350);
PAINT AQUA (-200 350);
DISPLAY INVISIBLE (-200 350);
FORCEADD CAP_A..1
(-525 250);
FORCEPROP 1 LASTPIN (-525 350) $PN 1
J 0
(-515 330);
DISPLAY 0.617021 (-515 330);
PAINT ORANGE (-515 330);
FORCEPROP 1 LASTPIN (-525 150) $PN 2
J 0
(-515 130);
DISPLAY 0.617021 (-515 130);
PAINT ORANGE (-515 130);
FORCEPROP 1 LAST VALUE 22.0UF
J 0
(-475 300);
DISPLAY 0.617021 (-475 300);
PAINT SKYBLUE (-475 300);
FORCEPROP 1 LAST TOLERANCE 20%
J 0
(-475 200);
DISPLAY 0.617021 (-475 200);
PAINT SKYBLUE (-475 200);
FORCEPROP 1 LAST PACK_TYPE 0603V
J 0
(-475 50);
DISPLAY 0.617021 (-475 50);
PAINT SKYBLUE (-475 50);
FORCEPROP 1 LAST VOLTAGE 4V
J 0
(-475 250);
DISPLAY 0.617021 (-475 250);
PAINT SKYBLUE (-475 250);
FORCEPROP 1 LAST MATERIAL X6S
J 0
(-475 150);
DISPLAY 0.617021 (-475 150);
PAINT SKYBLUE (-475 150);
FORCEPROP 1 LAST PART_NUMBER E15431-004
J 0
(-475 100);
DISPLAY 0.617021 (-475 100);
PAINT BLUE (-475 100);
FORCEPROP 1 LAST LOCATION C2G3
J 0
(-475 350);
DISPLAY 0.617021 (-475 350);
PAINT AQUA (-475 350);
FORCEPROP 2 LAST CDS_LIB dev_discrete
J 0
(-525 250);
PAINT ORANGE (-525 250);
DISPLAY INVISIBLE (-525 250);
FORCEPROP 2 LAST CDS_LOCATION C2G3
J 0
(-475 350);
DISPLAY 0.617021 (-475 350);
PAINT AQUA (-475 350);
DISPLAY INVISIBLE (-475 350);
FORCEPROP 2 LAST CDS_SEC 1
J 0
(-475 400);
PAINT ORANGE (-475 400);
DISPLAY INVISIBLE (-475 400);
FORCEPROP 2 LAST SEC_TYPE 0603V
J 0
(-475 450);
DISPLAY 1.021277 (-475 450);
PAINT ORANGE (-475 450);
DISPLAY INVISIBLE (-475 450);
FORCEPROP 2 LAST SEC 1
J 0
(-475 450);
DISPLAY 0.680851 (-475 450);
PAINT MONO (-475 450);
DISPLAY INVISIBLE (-475 450);
FORCEPROP 1 LAST PATH I216
J 0
(-475 400);
DISPLAY 0.978723 (-475 400);
PAINT WHITE (-475 400);
DISPLAY INVISIBLE (-475 400);
FORCEPROP 0 LAST ROOM PVDDQ_GHJ
J 0
(-475 450);
DISPLAY 1.021277 (-475 450);
PAINT ORANGE (-475 450);
DISPLAY INVISIBLE (-475 450);
FORCEADD CAP_A..1
(-825 250);
FORCEPROP 1 LASTPIN (-825 150) $PN 2
J 0
(-815 130);
DISPLAY 0.617021 (-815 130);
PAINT ORANGE (-815 130);
FORCEPROP 1 LASTPIN (-825 350) $PN 1
J 0
(-815 330);
DISPLAY 0.617021 (-815 330);
PAINT ORANGE (-815 330);
FORCEPROP 1 LAST LOCATION C2G2
J 0
(-775 350);
DISPLAY 0.617021 (-775 350);
PAINT AQUA (-775 350);
FORCEPROP 1 LAST VALUE 22.0UF
J 0
(-775 300);
DISPLAY 0.617021 (-775 300);
PAINT SKYBLUE (-775 300);
FORCEPROP 1 LAST TOLERANCE 20%
J 0
(-775 200);
DISPLAY 0.617021 (-775 200);
PAINT SKYBLUE (-775 200);
FORCEPROP 1 LAST PACK_TYPE 0603V
J 0
(-775 50);
DISPLAY 0.617021 (-775 50);
PAINT SKYBLUE (-775 50);
FORCEPROP 1 LAST VOLTAGE 4V
J 0
(-775 250);
DISPLAY 0.617021 (-775 250);
PAINT SKYBLUE (-775 250);
FORCEPROP 1 LAST MATERIAL X6S
J 0
(-775 150);
DISPLAY 0.617021 (-775 150);
PAINT SKYBLUE (-775 150);
FORCEPROP 1 LAST PART_NUMBER E15431-004
J 0
(-775 100);
DISPLAY 0.617021 (-775 100);
PAINT BLUE (-775 100);
FORCEPROP 2 LAST CDS_LIB dev_discrete
J 0
(-825 250);
PAINT ORANGE (-825 250);
DISPLAY INVISIBLE (-825 250);
FORCEPROP 2 LAST CDS_LOCATION C2G2
J 0
(-775 350);
DISPLAY 0.617021 (-775 350);
PAINT AQUA (-775 350);
DISPLAY INVISIBLE (-775 350);
FORCEPROP 1 LAST PATH I217
J 0
(-775 400);
DISPLAY 0.978723 (-775 400);
PAINT WHITE (-775 400);
DISPLAY INVISIBLE (-775 400);
FORCEPROP 2 LAST SEC 1
J 0
(-775 450);
DISPLAY 0.680851 (-775 450);
PAINT MONO (-775 450);
DISPLAY INVISIBLE (-775 450);
FORCEPROP 2 LAST SEC_TYPE 0603V
J 0
(-775 450);
DISPLAY 1.021277 (-775 450);
PAINT ORANGE (-775 450);
DISPLAY INVISIBLE (-775 450);
FORCEPROP 2 LAST CDS_SEC 1
J 0
(-775 400);
PAINT ORANGE (-775 400);
DISPLAY INVISIBLE (-775 400);
FORCEPROP 0 LAST ROOM PVDDQ_GHJ
J 0
(-775 450);
DISPLAY 1.021277 (-775 450);
PAINT ORANGE (-775 450);
DISPLAY INVISIBLE (-775 450);
FORCEADD CAP_A..1
(-1125 250);
FORCEPROP 1 LASTPIN (-1125 150) $PN 2
J 0
(-1115 130);
DISPLAY 0.617021 (-1115 130);
PAINT ORANGE (-1115 130);
FORCEPROP 1 LASTPIN (-1125 350) $PN 1
J 0
(-1115 330);
DISPLAY 0.617021 (-1115 330);
PAINT ORANGE (-1115 330);
FORCEPROP 1 LAST LOCATION C2G9
J 0
(-1075 350);
DISPLAY 0.617021 (-1075 350);
PAINT AQUA (-1075 350);
FORCEPROP 1 LAST PART_NUMBER E15431-004
J 0
(-1075 100);
DISPLAY 0.617021 (-1075 100);
PAINT BLUE (-1075 100);
FORCEPROP 1 LAST VALUE 22.0UF
J 0
(-1075 300);
DISPLAY 0.617021 (-1075 300);
PAINT SKYBLUE (-1075 300);
FORCEPROP 1 LAST TOLERANCE 20%
J 0
(-1075 200);
DISPLAY 0.617021 (-1075 200);
PAINT SKYBLUE (-1075 200);
FORCEPROP 1 LAST PACK_TYPE 0603V
J 0
(-1075 50);
DISPLAY 0.617021 (-1075 50);
PAINT SKYBLUE (-1075 50);
FORCEPROP 1 LAST VOLTAGE 4V
J 0
(-1075 250);
DISPLAY 0.617021 (-1075 250);
PAINT SKYBLUE (-1075 250);
FORCEPROP 1 LAST MATERIAL X6S
J 0
(-1075 150);
DISPLAY 0.617021 (-1075 150);
PAINT SKYBLUE (-1075 150);
FORCEPROP 2 LAST CDS_LIB dev_discrete
J 0
(-1125 250);
PAINT ORANGE (-1125 250);
DISPLAY INVISIBLE (-1125 250);
FORCEPROP 2 LAST CDS_LOCATION C2G9
J 0
(-1075 350);
DISPLAY 0.617021 (-1075 350);
PAINT AQUA (-1075 350);
DISPLAY INVISIBLE (-1075 350);
FORCEPROP 1 LAST PATH I218
J 0
(-1075 400);
DISPLAY 0.978723 (-1075 400);
PAINT WHITE (-1075 400);
DISPLAY INVISIBLE (-1075 400);
FORCEPROP 2 LAST SEC 1
J 0
(-1075 450);
DISPLAY 0.680851 (-1075 450);
PAINT MONO (-1075 450);
DISPLAY INVISIBLE (-1075 450);
FORCEPROP 2 LAST SEC_TYPE 0603V
J 0
(-1075 450);
DISPLAY 1.021277 (-1075 450);
PAINT ORANGE (-1075 450);
DISPLAY INVISIBLE (-1075 450);
FORCEPROP 2 LAST CDS_SEC 1
J 0
(-1075 400);
PAINT ORANGE (-1075 400);
DISPLAY INVISIBLE (-1075 400);
FORCEPROP 0 LAST ROOM PVDDQ_ABC
J 0
(-1075 450);
DISPLAY 1.021277 (-1075 450);
PAINT ORANGE (-1075 450);
DISPLAY INVISIBLE (-1075 450);
FORCEADD CAP_A..1
(-1400 250);
FORCEPROP 1 LASTPIN (-1400 150) $PN 2
J 0
(-1390 130);
DISPLAY 0.617021 (-1390 130);
PAINT ORANGE (-1390 130);
FORCEPROP 1 LAST VOLTAGE 4V
J 0
(-1350 250);
DISPLAY 0.617021 (-1350 250);
PAINT SKYBLUE (-1350 250);
FORCEPROP 1 LASTPIN (-1400 350) $PN 1
J 0
(-1390 330);
DISPLAY 0.617021 (-1390 330);
PAINT ORANGE (-1390 330);
FORCEPROP 1 LAST LOCATION C2G1
J 0
(-1350 350);
DISPLAY 0.617021 (-1350 350);
PAINT AQUA (-1350 350);
FORCEPROP 1 LAST PART_NUMBER E15431-004
J 0
(-1350 100);
DISPLAY 0.617021 (-1350 100);
PAINT BLUE (-1350 100);
FORCEPROP 1 LAST VALUE 22.0UF
J 0
(-1350 300);
DISPLAY 0.617021 (-1350 300);
PAINT SKYBLUE (-1350 300);
FORCEPROP 1 LAST TOLERANCE 20%
J 0
(-1350 200);
DISPLAY 0.617021 (-1350 200);
PAINT SKYBLUE (-1350 200);
FORCEPROP 1 LAST PACK_TYPE 0603V
J 0
(-1350 50);
DISPLAY 0.617021 (-1350 50);
PAINT SKYBLUE (-1350 50);
FORCEPROP 1 LAST MATERIAL X6S
J 0
(-1350 150);
DISPLAY 0.617021 (-1350 150);
PAINT SKYBLUE (-1350 150);
FORCEPROP 2 LAST CDS_LIB dev_discrete
J 0
(-1400 250);
PAINT ORANGE (-1400 250);
DISPLAY INVISIBLE (-1400 250);
FORCEPROP 2 LAST CDS_SEC 1
J 0
(-1350 400);
PAINT ORANGE (-1350 400);
DISPLAY INVISIBLE (-1350 400);
FORCEPROP 2 LAST CDS_LOCATION C2G1
J 0
(-1350 350);
DISPLAY 0.617021 (-1350 350);
PAINT AQUA (-1350 350);
DISPLAY INVISIBLE (-1350 350);
FORCEPROP 2 LAST SEC 1
J 0
(-1350 450);
DISPLAY 0.680851 (-1350 450);
PAINT MONO (-1350 450);
DISPLAY INVISIBLE (-1350 450);
FORCEPROP 2 LAST SEC_TYPE 0603V
J 0
(-1350 450);
DISPLAY 1.021277 (-1350 450);
PAINT ORANGE (-1350 450);
DISPLAY INVISIBLE (-1350 450);
FORCEPROP 0 LAST ROOM PVDDQ_GHJ
J 0
(-1350 450);
DISPLAY 1.021277 (-1350 450);
PAINT ORANGE (-1350 450);
DISPLAY INVISIBLE (-1350 450);
FORCEPROP 1 LAST PATH I219
J 0
(-1350 400);
DISPLAY 0.978723 (-1350 400);
PAINT WHITE (-1350 400);
DISPLAY INVISIBLE (-1350 400);
FORCEADD CAP_A..1
(-1675 250);
FORCEPROP 1 LASTPIN (-1675 150) $PN 2
J 0
(-1665 130);
DISPLAY 0.617021 (-1665 130);
PAINT ORANGE (-1665 130);
FORCEPROP 1 LAST MATERIAL X6S
J 0
(-1625 150);
DISPLAY 0.617021 (-1625 150);
PAINT SKYBLUE (-1625 150);
FORCEPROP 1 LAST TOLERANCE 20%
J 0
(-1625 200);
DISPLAY 0.617021 (-1625 200);
PAINT SKYBLUE (-1625 200);
FORCEPROP 1 LAST VOLTAGE 4V
J 0
(-1625 250);
DISPLAY 0.617021 (-1625 250);
PAINT SKYBLUE (-1625 250);
FORCEPROP 1 LASTPIN (-1675 350) $PN 1
J 0
(-1665 330);
DISPLAY 0.617021 (-1665 330);
PAINT ORANGE (-1665 330);
FORCEPROP 1 LAST LOCATION C2G12
J 0
(-1625 350);
DISPLAY 0.617021 (-1625 350);
PAINT AQUA (-1625 350);
FORCEPROP 1 LAST PART_NUMBER E15431-004
J 0
(-1625 100);
DISPLAY 0.617021 (-1625 100);
PAINT BLUE (-1625 100);
FORCEPROP 1 LAST VALUE 22.0UF
J 0
(-1625 300);
DISPLAY 0.617021 (-1625 300);
PAINT SKYBLUE (-1625 300);
FORCEPROP 1 LAST PACK_TYPE 0603V
J 0
(-1625 50);
DISPLAY 0.617021 (-1625 50);
PAINT SKYBLUE (-1625 50);
FORCEPROP 2 LAST CDS_LIB dev_discrete
J 0
(-1675 250);
PAINT ORANGE (-1675 250);
DISPLAY INVISIBLE (-1675 250);
FORCEPROP 1 LAST PATH I220
J 0
(-1625 400);
DISPLAY 0.978723 (-1625 400);
PAINT WHITE (-1625 400);
DISPLAY INVISIBLE (-1625 400);
FORCEPROP 0 LAST ROOM PVDDQ_GHJ
J 0
(-1625 450);
DISPLAY 1.021277 (-1625 450);
PAINT ORANGE (-1625 450);
DISPLAY INVISIBLE (-1625 450);
FORCEPROP 2 LAST SEC 1
J 0
(-1625 450);
DISPLAY 0.680851 (-1625 450);
PAINT MONO (-1625 450);
DISPLAY INVISIBLE (-1625 450);
FORCEPROP 2 LAST SEC_TYPE 0603V
J 0
(-1625 450);
DISPLAY 1.021277 (-1625 450);
PAINT ORANGE (-1625 450);
DISPLAY INVISIBLE (-1625 450);
FORCEPROP 2 LAST CDS_SEC 1
J 0
(-1625 400);
PAINT ORANGE (-1625 400);
DISPLAY INVISIBLE (-1625 400);
FORCEPROP 2 LAST CDS_LOCATION C2G12
J 0
(-1625 350);
DISPLAY 0.617021 (-1625 350);
PAINT AQUA (-1625 350);
DISPLAY INVISIBLE (-1625 350);
FORCEADD CAP_A..1
(-1975 250);
FORCEPROP 1 LASTPIN (-1975 150) $PN 2
J 0
(-1965 130);
DISPLAY 0.617021 (-1965 130);
PAINT ORANGE (-1965 130);
FORCEPROP 1 LAST MATERIAL X6S
J 0
(-1925 150);
DISPLAY 0.617021 (-1925 150);
PAINT SKYBLUE (-1925 150);
FORCEPROP 1 LAST TOLERANCE 20%
J 0
(-1925 200);
DISPLAY 0.617021 (-1925 200);
PAINT SKYBLUE (-1925 200);
FORCEPROP 1 LAST VOLTAGE 4V
J 0
(-1925 250);
DISPLAY 0.617021 (-1925 250);
PAINT SKYBLUE (-1925 250);
FORCEPROP 1 LASTPIN (-1975 350) $PN 1
J 0
(-1965 330);
DISPLAY 0.617021 (-1965 330);
PAINT ORANGE (-1965 330);
FORCEPROP 1 LAST LOCATION C2G11
J 0
(-1925 350);
DISPLAY 0.617021 (-1925 350);
PAINT AQUA (-1925 350);
FORCEPROP 1 LAST PART_NUMBER E15431-004
J 0
(-1925 100);
DISPLAY 0.617021 (-1925 100);
PAINT BLUE (-1925 100);
FORCEPROP 1 LAST VALUE 22.0UF
J 0
(-1925 300);
DISPLAY 0.617021 (-1925 300);
PAINT SKYBLUE (-1925 300);
FORCEPROP 1 LAST PACK_TYPE 0603V
J 0
(-1925 50);
DISPLAY 0.617021 (-1925 50);
PAINT SKYBLUE (-1925 50);
FORCEPROP 2 LAST CDS_LIB dev_discrete
J 0
(-1975 250);
PAINT ORANGE (-1975 250);
DISPLAY INVISIBLE (-1975 250);
FORCEPROP 2 LAST CDS_LOCATION C2G11
J 0
(-1925 350);
DISPLAY 0.617021 (-1925 350);
PAINT AQUA (-1925 350);
DISPLAY INVISIBLE (-1925 350);
FORCEPROP 2 LAST CDS_SEC 1
J 0
(-1925 400);
PAINT ORANGE (-1925 400);
DISPLAY INVISIBLE (-1925 400);
FORCEPROP 2 LAST SEC_TYPE 0603V
J 0
(-1925 450);
DISPLAY 1.021277 (-1925 450);
PAINT ORANGE (-1925 450);
DISPLAY INVISIBLE (-1925 450);
FORCEPROP 2 LAST SEC 1
J 0
(-1925 450);
DISPLAY 0.680851 (-1925 450);
PAINT MONO (-1925 450);
DISPLAY INVISIBLE (-1925 450);
FORCEPROP 1 LAST PATH I221
J 0
(-1925 400);
DISPLAY 0.978723 (-1925 400);
PAINT WHITE (-1925 400);
DISPLAY INVISIBLE (-1925 400);
FORCEPROP 0 LAST ROOM PVDDQ_GHJ
J 0
(-1925 450);
DISPLAY 1.021277 (-1925 450);
PAINT ORANGE (-1925 450);
DISPLAY INVISIBLE (-1925 450);
FORCEADD PVDDQ_GHJ..1
(-2275 500);
FORCEPROP 3 LASTPIN (-2275 450) SIG_NAME PVDDQ_GHJ\g
J 0
(-2265 460);
DISPLAY 0.659574 (-2265 460);
PAINT MONO (-2265 460);
DISPLAY INVISIBLE (-2265 460);
FORCEPROP 1 LAST VOLTAGE 1.2V
J 0
(-2320 457);
DISPLAY 0.340426 (-2320 457);
PAINT SKYBLUE (-2320 457);
DISPLAY INVISIBLE (-2320 457);
FORCEPROP 1 LAST BODY_TYPE PLUMBING
J 0
(-2320 457);
DISPLAY 0.340426 (-2320 457);
PAINT GREEN (-2320 457);
DISPLAY INVISIBLE (-2320 457);
FORCEPROP 2 LAST CDS_LIB mstr_symbols
J 0
(-2275 500);
PAINT ORANGE (-2275 500);
DISPLAY INVISIBLE (-2275 500);
FORCEPROP 1 LAST PATH I222
J 0
(-2225 525);
DISPLAY 0.872340 (-2225 525);
PAINT AQUA (-2225 525);
DISPLAY INVISIBLE (-2225 525);
FORCEPROP 1 LAST HDL_POWER PVDDQ_GHJ
J 1
(-2275 550);
DISPLAY 0.872340 (-2275 550);
PAINT GREEN (-2275 550);
DISPLAY INVISIBLE (-2275 550);
FORCEADD CAP_A..1
(-2275 250);
FORCEPROP 1 LASTPIN (-2275 150) $PN 2
J 0
(-2265 130);
DISPLAY 0.617021 (-2265 130);
PAINT ORANGE (-2265 130);
FORCEPROP 1 LAST MATERIAL X6S
J 0
(-2225 150);
DISPLAY 0.617021 (-2225 150);
PAINT SKYBLUE (-2225 150);
FORCEPROP 1 LAST PACK_TYPE 0603V
J 0
(-2225 50);
DISPLAY 0.617021 (-2225 50);
PAINT SKYBLUE (-2225 50);
FORCEPROP 1 LAST TOLERANCE 20%
J 0
(-2225 200);
DISPLAY 0.617021 (-2225 200);
PAINT SKYBLUE (-2225 200);
FORCEPROP 1 LAST VOLTAGE 4V
J 0
(-2225 250);
DISPLAY 0.617021 (-2225 250);
PAINT SKYBLUE (-2225 250);
FORCEPROP 1 LASTPIN (-2275 350) $PN 1
J 0
(-2265 330);
DISPLAY 0.617021 (-2265 330);
PAINT ORANGE (-2265 330);
FORCEPROP 1 LAST LOCATION C2G10
J 0
(-2225 350);
DISPLAY 0.617021 (-2225 350);
PAINT AQUA (-2225 350);
FORCEPROP 1 LAST VALUE 22.0UF
J 0
(-2225 300);
DISPLAY 0.617021 (-2225 300);
PAINT SKYBLUE (-2225 300);
FORCEPROP 1 LAST PART_NUMBER E15431-004
J 0
(-2225 100);
DISPLAY 0.617021 (-2225 100);
PAINT BLUE (-2225 100);
FORCEPROP 2 LAST CDS_LIB dev_discrete
J 0
(-2275 250);
PAINT ORANGE (-2275 250);
DISPLAY INVISIBLE (-2275 250);
FORCEPROP 2 LAST CDS_LOCATION C2G10
J 0
(-2225 350);
DISPLAY 0.617021 (-2225 350);
PAINT AQUA (-2225 350);
DISPLAY INVISIBLE (-2225 350);
FORCEPROP 1 LAST PATH I223
J 0
(-2225 400);
DISPLAY 0.978723 (-2225 400);
PAINT WHITE (-2225 400);
DISPLAY INVISIBLE (-2225 400);
FORCEPROP 0 LAST ROOM PVDDQ_GHJ
J 0
(-2225 450);
DISPLAY 1.021277 (-2225 450);
PAINT ORANGE (-2225 450);
DISPLAY INVISIBLE (-2225 450);
FORCEPROP 2 LAST SEC 1
J 0
(-2225 450);
DISPLAY 0.680851 (-2225 450);
PAINT MONO (-2225 450);
DISPLAY INVISIBLE (-2225 450);
FORCEPROP 2 LAST CDS_SEC 1
J 0
(-2225 400);
PAINT ORANGE (-2225 400);
DISPLAY INVISIBLE (-2225 400);
FORCEPROP 2 LAST SEC_TYPE 0603V
J 0
(-2225 450);
DISPLAY 1.021277 (-2225 450);
PAINT ORANGE (-2225 450);
DISPLAY INVISIBLE (-2225 450);
FORCEADD GND..1
(-2275 -25);
FORCEPROP 3 LASTPIN (-2275 25) SIG_NAME GND\g
J 0
(-2265 35);
DISPLAY 0.659574 (-2265 35);
PAINT MONO (-2265 35);
DISPLAY INVISIBLE (-2265 35);
FORCEPROP 1 LAST BODY_TYPE PLUMBING
J 0
(-2320 -68);
DISPLAY 0.340426 (-2320 -68);
PAINT GREEN (-2320 -68);
DISPLAY INVISIBLE (-2320 -68);
FORCEPROP 1 LAST SIZE 1B
J 0
(-2200 -75);
DISPLAY 1.723404 (-2200 -75);
PAINT GREEN (-2200 -75);
DISPLAY INVISIBLE (-2200 -75);
FORCEPROP 1 LAST VOLTAGE 0
J 0
(-2275 -25);
PAINT SKYBLUE (-2275 -25);
DISPLAY INVISIBLE (-2275 -25);
FORCEPROP 2 LAST CDS_LIB mstr_symbols
J 0
(-2275 -25);
PAINT ORANGE (-2275 -25);
DISPLAY INVISIBLE (-2275 -25);
FORCEPROP 1 LAST PATH I224
J 0
(-2200 -25);
DISPLAY 0.872340 (-2200 -25);
PAINT AQUA (-2200 -25);
DISPLAY INVISIBLE (-2200 -25);
FORCEPROP 2 LAST BOM_COST PROC_VRD_VCCIN_CPU0
J 0
(-2650 50);
DISPLAY 1.446809 (-2650 50);
PAINT MONO (-2650 50);
DISPLAY INVISIBLE (-2650 50);
FORCEPROP 2 LAST ROOM VDDQ_ABC_PWR_VR
J 0
(-2825 50);
DISPLAY 1.936170 (-2825 50);
PAINT ORANGE (-2825 50);
DISPLAY INVISIBLE (-2825 50);
FORCEPROP 1 LAST HDL_POWER GND
J 0
(-2275 125);
DISPLAY 1.723404 (-2275 125);
PAINT GREEN (-2275 125);
DISPLAY INVISIBLE (-2275 125);
FORCEADD CAP_A..1
(2125 -450);
FORCEPROP 1 LAST MATERIAL X6S
J 0
(2175 -550);
DISPLAY 0.617021 (2175 -550);
PAINT SKYBLUE (2175 -550);
FORCEPROP 1 LAST PACK_TYPE 0603V
J 0
(2175 -650);
DISPLAY 0.617021 (2175 -650);
PAINT SKYBLUE (2175 -650);
FORCEPROP 1 LAST PART_NUMBER E15431-004
J 0
(2175 -600);
DISPLAY 0.617021 (2175 -600);
PAINT BLUE (2175 -600);
FORCEPROP 1 LASTPIN (2125 -550) $PN 2
J 0
(2135 -570);
DISPLAY 0.617021 (2135 -570);
PAINT ORANGE (2135 -570);
FORCEPROP 1 LASTPIN (2125 -350) $PN 1
J 0
(2135 -370);
DISPLAY 0.617021 (2135 -370);
PAINT ORANGE (2135 -370);
FORCEPROP 1 LAST LOCATION C8U4
J 0
(2175 -350);
DISPLAY 0.617021 (2175 -350);
PAINT AQUA (2175 -350);
FORCEPROP 1 LAST TOLERANCE 20%
J 0
(2175 -500);
DISPLAY 0.617021 (2175 -500);
PAINT SKYBLUE (2175 -500);
FORCEPROP 1 LAST VOLTAGE 4V
J 0
(2175 -450);
DISPLAY 0.617021 (2175 -450);
PAINT SKYBLUE (2175 -450);
FORCEPROP 1 LAST VALUE 22.0UF
J 0
(2175 -400);
DISPLAY 0.617021 (2175 -400);
PAINT SKYBLUE (2175 -400);
FORCEPROP 2 LAST SEC 1
J 0
(2175 -300);
DISPLAY 0.680851 (2175 -300);
PAINT MONO (2175 -300);
DISPLAY INVISIBLE (2175 -300);
FORCEPROP 2 LAST CDS_SEC 1
J 0
(2175 -300);
PAINT ORANGE (2175 -300);
DISPLAY INVISIBLE (2175 -300);
FORCEPROP 2 LAST CDS_LIB dev_discrete
J 0
(2125 -450);
PAINT ORANGE (2125 -450);
DISPLAY INVISIBLE (2125 -450);
FORCEPROP 2 LAST CDS_LOCATION C8U4
J 0
(2175 -350);
DISPLAY 0.617021 (2175 -350);
PAINT AQUA (2175 -350);
DISPLAY INVISIBLE (2175 -350);
FORCEPROP 1 LAST PATH I225
J 0
(2175 -300);
DISPLAY 0.978723 (2175 -300);
PAINT WHITE (2175 -300);
DISPLAY INVISIBLE (2175 -300);
FORCEPROP 0 LAST ROOM PVDDQ_GHJ
J 0
(2175 -250);
DISPLAY 1.021277 (2175 -250);
PAINT ORANGE (2175 -250);
DISPLAY INVISIBLE (2175 -250);
FORCEPROP 2 LAST SEC_TYPE 0603V
J 0
(2175 -250);
DISPLAY 1.021277 (2175 -250);
PAINT ORANGE (2175 -250);
DISPLAY INVISIBLE (2175 -250);
FORCEADD CAP_A..1
(1850 -450);
FORCEPROP 1 LASTPIN (1850 -550) $PN 2
J 0
(1860 -570);
DISPLAY 0.617021 (1860 -570);
PAINT ORANGE (1860 -570);
FORCEPROP 1 LAST MATERIAL X6S
J 0
(1900 -550);
DISPLAY 0.617021 (1900 -550);
PAINT SKYBLUE (1900 -550);
FORCEPROP 1 LAST PACK_TYPE 0603V
J 0
(1900 -650);
DISPLAY 0.617021 (1900 -650);
PAINT SKYBLUE (1900 -650);
FORCEPROP 1 LASTPIN (1850 -350) $PN 1
J 0
(1860 -370);
DISPLAY 0.617021 (1860 -370);
PAINT ORANGE (1860 -370);
FORCEPROP 1 LAST TOLERANCE 20%
J 0
(1900 -500);
DISPLAY 0.617021 (1900 -500);
PAINT SKYBLUE (1900 -500);
FORCEPROP 1 LAST VOLTAGE 4V
J 0
(1900 -450);
DISPLAY 0.617021 (1900 -450);
PAINT SKYBLUE (1900 -450);
FORCEPROP 1 LAST PART_NUMBER E15431-004
J 0
(1900 -600);
DISPLAY 0.617021 (1900 -600);
PAINT BLUE (1900 -600);
FORCEPROP 1 LAST VALUE 22.0UF
J 0
(1900 -400);
DISPLAY 0.617021 (1900 -400);
PAINT SKYBLUE (1900 -400);
FORCEPROP 1 LAST LOCATION C8T10
J 0
(1900 -350);
DISPLAY 0.617021 (1900 -350);
PAINT AQUA (1900 -350);
FORCEPROP 2 LAST CDS_LIB dev_discrete
J 0
(1850 -450);
PAINT ORANGE (1850 -450);
DISPLAY INVISIBLE (1850 -450);
FORCEPROP 1 LAST PATH I226
J 0
(1900 -300);
DISPLAY 0.978723 (1900 -300);
PAINT WHITE (1900 -300);
DISPLAY INVISIBLE (1900 -300);
FORCEPROP 2 LAST SEC 1
J 0
(1900 -300);
DISPLAY 0.680851 (1900 -300);
PAINT MONO (1900 -300);
DISPLAY INVISIBLE (1900 -300);
FORCEPROP 2 LAST CDS_SEC 1
J 0
(1900 -300);
PAINT ORANGE (1900 -300);
DISPLAY INVISIBLE (1900 -300);
FORCEPROP 2 LAST CDS_LOCATION C8T10
J 0
(1900 -350);
DISPLAY 0.617021 (1900 -350);
PAINT AQUA (1900 -350);
DISPLAY INVISIBLE (1900 -350);
FORCEPROP 0 LAST ROOM PVDDQ_GHJ
J 0
(1900 -250);
DISPLAY 1.021277 (1900 -250);
PAINT ORANGE (1900 -250);
DISPLAY INVISIBLE (1900 -250);
FORCEPROP 2 LAST SEC_TYPE 0603V
J 0
(1900 -250);
DISPLAY 1.021277 (1900 -250);
PAINT ORANGE (1900 -250);
DISPLAY INVISIBLE (1900 -250);
FORCEADD CAP_A..1
(1550 -450);
FORCEPROP 1 LASTPIN (1550 -550) $PN 2
J 0
(1560 -570);
DISPLAY 0.617021 (1560 -570);
PAINT ORANGE (1560 -570);
FORCEPROP 1 LAST MATERIAL X6S
J 0
(1600 -550);
DISPLAY 0.617021 (1600 -550);
PAINT SKYBLUE (1600 -550);
FORCEPROP 1 LAST PACK_TYPE 0603V
J 0
(1600 -650);
DISPLAY 0.617021 (1600 -650);
PAINT SKYBLUE (1600 -650);
FORCEPROP 1 LAST PART_NUMBER E15431-004
J 0
(1600 -600);
DISPLAY 0.617021 (1600 -600);
PAINT BLUE (1600 -600);
FORCEPROP 1 LAST VOLTAGE 4V
J 0
(1600 -450);
DISPLAY 0.617021 (1600 -450);
PAINT SKYBLUE (1600 -450);
FORCEPROP 1 LASTPIN (1550 -350) $PN 1
J 0
(1560 -370);
DISPLAY 0.617021 (1560 -370);
PAINT ORANGE (1560 -370);
FORCEPROP 1 LAST TOLERANCE 20%
J 0
(1600 -500);
DISPLAY 0.617021 (1600 -500);
PAINT SKYBLUE (1600 -500);
FORCEPROP 1 LAST VALUE 22.0UF
J 0
(1600 -400);
DISPLAY 0.617021 (1600 -400);
PAINT SKYBLUE (1600 -400);
FORCEPROP 1 LAST LOCATION C8T9
J 0
(1600 -350);
DISPLAY 0.617021 (1600 -350);
PAINT AQUA (1600 -350);
FORCEPROP 2 LAST CDS_LIB dev_discrete
J 0
(1550 -450);
PAINT ORANGE (1550 -450);
DISPLAY INVISIBLE (1550 -450);
FORCEPROP 1 LAST PATH I227
J 0
(1600 -300);
DISPLAY 0.978723 (1600 -300);
PAINT WHITE (1600 -300);
DISPLAY INVISIBLE (1600 -300);
FORCEPROP 2 LAST SEC 1
J 0
(1600 -300);
DISPLAY 0.680851 (1600 -300);
PAINT MONO (1600 -300);
DISPLAY INVISIBLE (1600 -300);
FORCEPROP 2 LAST CDS_SEC 1
J 0
(1600 -300);
PAINT ORANGE (1600 -300);
DISPLAY INVISIBLE (1600 -300);
FORCEPROP 2 LAST CDS_LOCATION C8T9
J 0
(1600 -350);
DISPLAY 0.617021 (1600 -350);
PAINT AQUA (1600 -350);
DISPLAY INVISIBLE (1600 -350);
FORCEPROP 0 LAST ROOM PVDDQ_GHJ
J 0
(1600 -250);
DISPLAY 1.021277 (1600 -250);
PAINT ORANGE (1600 -250);
DISPLAY INVISIBLE (1600 -250);
FORCEPROP 2 LAST SEC_TYPE 0603V
J 0
(1600 -250);
DISPLAY 1.021277 (1600 -250);
PAINT ORANGE (1600 -250);
DISPLAY INVISIBLE (1600 -250);
FORCEADD CAP_A..1
(1250 -450);
FORCEPROP 1 LAST PACK_TYPE 0603V
J 0
(1300 -650);
DISPLAY 0.617021 (1300 -650);
PAINT SKYBLUE (1300 -650);
FORCEPROP 1 LAST MATERIAL X6S
J 0
(1300 -550);
DISPLAY 0.617021 (1300 -550);
PAINT SKYBLUE (1300 -550);
FORCEPROP 1 LASTPIN (1250 -550) $PN 2
J 0
(1260 -570);
DISPLAY 0.617021 (1260 -570);
PAINT ORANGE (1260 -570);
FORCEPROP 1 LASTPIN (1250 -350) $PN 1
J 0
(1260 -370);
DISPLAY 0.617021 (1260 -370);
PAINT ORANGE (1260 -370);
FORCEPROP 1 LAST LOCATION C8U5
J 0
(1300 -350);
DISPLAY 0.617021 (1300 -350);
PAINT AQUA (1300 -350);
FORCEPROP 1 LAST VALUE 22.0UF
J 0
(1300 -400);
DISPLAY 0.617021 (1300 -400);
PAINT SKYBLUE (1300 -400);
FORCEPROP 1 LAST TOLERANCE 20%
J 0
(1300 -500);
DISPLAY 0.617021 (1300 -500);
PAINT SKYBLUE (1300 -500);
FORCEPROP 1 LAST VOLTAGE 4V
J 0
(1300 -450);
DISPLAY 0.617021 (1300 -450);
PAINT SKYBLUE (1300 -450);
FORCEPROP 1 LAST PART_NUMBER E15431-004
J 0
(1300 -600);
DISPLAY 0.617021 (1300 -600);
PAINT BLUE (1300 -600);
FORCEPROP 2 LAST CDS_LIB dev_discrete
J 0
(1250 -450);
PAINT ORANGE (1250 -450);
DISPLAY INVISIBLE (1250 -450);
FORCEPROP 2 LAST CDS_LOCATION C8U5
J 0
(1300 -350);
DISPLAY 0.617021 (1300 -350);
PAINT AQUA (1300 -350);
DISPLAY INVISIBLE (1300 -350);
FORCEPROP 2 LAST CDS_SEC 1
J 0
(1300 -300);
PAINT ORANGE (1300 -300);
DISPLAY INVISIBLE (1300 -300);
FORCEPROP 2 LAST SEC_TYPE 0603V
J 0
(1300 -250);
DISPLAY 1.021277 (1300 -250);
PAINT ORANGE (1300 -250);
DISPLAY INVISIBLE (1300 -250);
FORCEPROP 2 LAST SEC 1
J 0
(1300 -250);
DISPLAY 0.680851 (1300 -250);
PAINT MONO (1300 -250);
DISPLAY INVISIBLE (1300 -250);
FORCEPROP 1 LAST PATH I228
J 0
(1300 -300);
DISPLAY 0.978723 (1300 -300);
PAINT WHITE (1300 -300);
DISPLAY INVISIBLE (1300 -300);
FORCEPROP 0 LAST ROOM PVDDQ_GHJ
J 0
(1300 -250);
DISPLAY 1.021277 (1300 -250);
PAINT ORANGE (1300 -250);
DISPLAY INVISIBLE (1300 -250);
FORCEADD CAP_A..1
(975 -450);
FORCEPROP 1 LASTPIN (975 -550) $PN 2
J 0
(985 -570);
DISPLAY 0.617021 (985 -570);
PAINT ORANGE (985 -570);
FORCEPROP 1 LASTPIN (975 -350) $PN 1
J 0
(985 -370);
DISPLAY 0.617021 (985 -370);
PAINT ORANGE (985 -370);
FORCEPROP 1 LAST MATERIAL X6S
J 0
(1025 -550);
DISPLAY 0.617021 (1025 -550);
PAINT SKYBLUE (1025 -550);
FORCEPROP 1 LAST PACK_TYPE 0603V
J 0
(1025 -650);
DISPLAY 0.617021 (1025 -650);
PAINT SKYBLUE (1025 -650);
FORCEPROP 1 LAST PART_NUMBER E15431-004
J 0
(1025 -600);
DISPLAY 0.617021 (1025 -600);
PAINT BLUE (1025 -600);
FORCEPROP 1 LAST LOCATION C8T8
J 0
(1025 -350);
DISPLAY 0.617021 (1025 -350);
PAINT AQUA (1025 -350);
FORCEPROP 1 LAST TOLERANCE 20%
J 0
(1025 -500);
DISPLAY 0.617021 (1025 -500);
PAINT SKYBLUE (1025 -500);
FORCEPROP 1 LAST VOLTAGE 4V
J 0
(1025 -450);
DISPLAY 0.617021 (1025 -450);
PAINT SKYBLUE (1025 -450);
FORCEPROP 1 LAST VALUE 22.0UF
J 0
(1025 -400);
DISPLAY 0.617021 (1025 -400);
PAINT SKYBLUE (1025 -400);
FORCEPROP 2 LAST CDS_LIB dev_discrete
J 0
(975 -450);
PAINT ORANGE (975 -450);
DISPLAY INVISIBLE (975 -450);
FORCEPROP 1 LAST PATH I229
J 0
(1025 -300);
DISPLAY 0.978723 (1025 -300);
PAINT WHITE (1025 -300);
DISPLAY INVISIBLE (1025 -300);
FORCEPROP 2 LAST SEC 1
J 0
(1025 -300);
DISPLAY 0.680851 (1025 -300);
PAINT MONO (1025 -300);
DISPLAY INVISIBLE (1025 -300);
FORCEPROP 2 LAST CDS_SEC 1
J 0
(1025 -300);
PAINT ORANGE (1025 -300);
DISPLAY INVISIBLE (1025 -300);
FORCEPROP 2 LAST CDS_LOCATION C8T8
J 0
(1025 -350);
DISPLAY 0.617021 (1025 -350);
PAINT AQUA (1025 -350);
DISPLAY INVISIBLE (1025 -350);
FORCEPROP 2 LAST SEC_TYPE 0603V
J 0
(1025 -250);
DISPLAY 1.021277 (1025 -250);
PAINT ORANGE (1025 -250);
DISPLAY INVISIBLE (1025 -250);
FORCEPROP 0 LAST ROOM PVDDQ_GHJ
J 0
(1025 -250);
DISPLAY 1.021277 (1025 -250);
PAINT ORANGE (1025 -250);
DISPLAY INVISIBLE (1025 -250);
FORCEADD CAP_A..1
(700 -450);
FORCEPROP 1 LASTPIN (700 -550) $PN 2
J 0
(710 -570);
DISPLAY 0.617021 (710 -570);
PAINT ORANGE (710 -570);
FORCEPROP 1 LAST MATERIAL X6S
J 0
(750 -550);
DISPLAY 0.617021 (750 -550);
PAINT SKYBLUE (750 -550);
FORCEPROP 1 LAST PACK_TYPE 0603V
J 0
(750 -650);
DISPLAY 0.617021 (750 -650);
PAINT SKYBLUE (750 -650);
FORCEPROP 1 LASTPIN (700 -350) $PN 1
J 0
(710 -370);
DISPLAY 0.617021 (710 -370);
PAINT ORANGE (710 -370);
FORCEPROP 1 LAST VOLTAGE 4V
J 0
(750 -450);
DISPLAY 0.617021 (750 -450);
PAINT SKYBLUE (750 -450);
FORCEPROP 1 LAST TOLERANCE 20%
J 0
(750 -500);
DISPLAY 0.617021 (750 -500);
PAINT SKYBLUE (750 -500);
FORCEPROP 1 LAST VALUE 22.0UF
J 0
(750 -400);
DISPLAY 0.617021 (750 -400);
PAINT SKYBLUE (750 -400);
FORCEPROP 1 LAST LOCATION C8T7
J 0
(750 -350);
DISPLAY 0.617021 (750 -350);
PAINT AQUA (750 -350);
FORCEPROP 1 LAST PART_NUMBER E15431-004
J 0
(750 -600);
DISPLAY 0.617021 (750 -600);
PAINT BLUE (750 -600);
FORCEPROP 2 LAST CDS_LIB dev_discrete
J 0
(700 -450);
PAINT ORANGE (700 -450);
DISPLAY INVISIBLE (700 -450);
FORCEPROP 2 LAST SEC 1
J 0
(750 -300);
DISPLAY 0.680851 (750 -300);
PAINT MONO (750 -300);
DISPLAY INVISIBLE (750 -300);
FORCEPROP 1 LAST PATH I230
J 0
(750 -300);
DISPLAY 0.978723 (750 -300);
PAINT WHITE (750 -300);
DISPLAY INVISIBLE (750 -300);
FORCEPROP 2 LAST CDS_LOCATION C8T7
J 0
(750 -350);
DISPLAY 0.617021 (750 -350);
PAINT AQUA (750 -350);
DISPLAY INVISIBLE (750 -350);
FORCEPROP 2 LAST CDS_SEC 1
J 0
(750 -300);
PAINT ORANGE (750 -300);
DISPLAY INVISIBLE (750 -300);
FORCEPROP 0 LAST ROOM PVDDQ_GHJ
J 0
(750 -250);
DISPLAY 1.021277 (750 -250);
PAINT ORANGE (750 -250);
DISPLAY INVISIBLE (750 -250);
FORCEPROP 2 LAST SEC_TYPE 0603V
J 0
(750 -250);
DISPLAY 1.021277 (750 -250);
PAINT ORANGE (750 -250);
DISPLAY INVISIBLE (750 -250);
FORCEADD CAP_A..1
(400 -450);
FORCEPROP 1 LASTPIN (400 -550) $PN 2
J 0
(410 -570);
DISPLAY 0.617021 (410 -570);
PAINT ORANGE (410 -570);
FORCEPROP 1 LAST VOLTAGE 4V
J 0
(450 -450);
DISPLAY 0.617021 (450 -450);
PAINT SKYBLUE (450 -450);
FORCEPROP 1 LASTPIN (400 -350) $PN 1
J 0
(410 -370);
DISPLAY 0.617021 (410 -370);
PAINT ORANGE (410 -370);
FORCEPROP 1 LAST LOCATION C8T6
J 0
(450 -350);
DISPLAY 0.617021 (450 -350);
PAINT AQUA (450 -350);
FORCEPROP 1 LAST PART_NUMBER E15431-004
J 0
(450 -600);
DISPLAY 0.617021 (450 -600);
PAINT BLUE (450 -600);
FORCEPROP 1 LAST VALUE 22.0UF
J 0
(450 -400);
DISPLAY 0.617021 (450 -400);
PAINT SKYBLUE (450 -400);
FORCEPROP 1 LAST TOLERANCE 20%
J 0
(450 -500);
DISPLAY 0.617021 (450 -500);
PAINT SKYBLUE (450 -500);
FORCEPROP 1 LAST PACK_TYPE 0603V
J 0
(450 -650);
DISPLAY 0.617021 (450 -650);
PAINT SKYBLUE (450 -650);
FORCEPROP 1 LAST MATERIAL X6S
J 0
(450 -550);
DISPLAY 0.617021 (450 -550);
PAINT SKYBLUE (450 -550);
FORCEPROP 2 LAST CDS_LIB dev_discrete
J 0
(400 -450);
PAINT ORANGE (400 -450);
DISPLAY INVISIBLE (400 -450);
FORCEPROP 1 LAST PATH I231
J 0
(450 -300);
DISPLAY 0.978723 (450 -300);
PAINT WHITE (450 -300);
DISPLAY INVISIBLE (450 -300);
FORCEPROP 2 LAST SEC 1
J 0
(450 -300);
DISPLAY 0.680851 (450 -300);
PAINT MONO (450 -300);
DISPLAY INVISIBLE (450 -300);
FORCEPROP 2 LAST CDS_SEC 1
J 0
(450 -300);
PAINT ORANGE (450 -300);
DISPLAY INVISIBLE (450 -300);
FORCEPROP 2 LAST CDS_LOCATION C8T6
J 0
(450 -350);
DISPLAY 0.617021 (450 -350);
PAINT AQUA (450 -350);
DISPLAY INVISIBLE (450 -350);
FORCEPROP 0 LAST ROOM PVDDQ_GHJ
J 0
(450 -250);
DISPLAY 1.021277 (450 -250);
PAINT ORANGE (450 -250);
DISPLAY INVISIBLE (450 -250);
FORCEPROP 2 LAST SEC_TYPE 0603V
J 0
(450 -250);
DISPLAY 1.021277 (450 -250);
PAINT ORANGE (450 -250);
DISPLAY INVISIBLE (450 -250);
FORCEADD CAP_A..1
(100 -450);
FORCEPROP 1 LASTPIN (100 -550) $PN 2
J 0
(110 -570);
DISPLAY 0.617021 (110 -570);
PAINT ORANGE (110 -570);
FORCEPROP 1 LAST MATERIAL X6S
J 0
(150 -550);
DISPLAY 0.617021 (150 -550);
PAINT SKYBLUE (150 -550);
FORCEPROP 1 LAST PACK_TYPE 0603V
J 0
(150 -650);
DISPLAY 0.617021 (150 -650);
PAINT SKYBLUE (150 -650);
FORCEPROP 1 LAST PART_NUMBER E15431-004
J 0
(150 -600);
DISPLAY 0.617021 (150 -600);
PAINT BLUE (150 -600);
FORCEPROP 1 LASTPIN (100 -350) $PN 1
J 0
(110 -370);
DISPLAY 0.617021 (110 -370);
PAINT ORANGE (110 -370);
FORCEPROP 1 LAST VOLTAGE 4V
J 0
(150 -450);
DISPLAY 0.617021 (150 -450);
PAINT SKYBLUE (150 -450);
FORCEPROP 1 LAST TOLERANCE 20%
J 0
(150 -500);
DISPLAY 0.617021 (150 -500);
PAINT SKYBLUE (150 -500);
FORCEPROP 1 LAST VALUE 22.0UF
J 0
(150 -400);
DISPLAY 0.617021 (150 -400);
PAINT SKYBLUE (150 -400);
FORCEPROP 1 LAST LOCATION C8U6
J 0
(150 -350);
DISPLAY 0.617021 (150 -350);
PAINT AQUA (150 -350);
FORCEPROP 2 LAST CDS_LIB dev_discrete
J 0
(100 -450);
PAINT ORANGE (100 -450);
DISPLAY INVISIBLE (100 -450);
FORCEPROP 2 LAST CDS_LOCATION C8U6
J 0
(150 -350);
DISPLAY 0.617021 (150 -350);
PAINT AQUA (150 -350);
DISPLAY INVISIBLE (150 -350);
FORCEPROP 2 LAST CDS_SEC 1
J 0
(150 -300);
PAINT ORANGE (150 -300);
DISPLAY INVISIBLE (150 -300);
FORCEPROP 1 LAST PATH I232
J 0
(150 -300);
DISPLAY 0.978723 (150 -300);
PAINT WHITE (150 -300);
DISPLAY INVISIBLE (150 -300);
FORCEPROP 0 LAST ROOM PVDDQ_GHJ
J 0
(150 -250);
DISPLAY 1.021277 (150 -250);
PAINT ORANGE (150 -250);
DISPLAY INVISIBLE (150 -250);
FORCEPROP 2 LAST SEC 1
J 0
(150 -250);
DISPLAY 0.680851 (150 -250);
PAINT MONO (150 -250);
DISPLAY INVISIBLE (150 -250);
FORCEPROP 2 LAST SEC_TYPE 0603V
J 0
(150 -250);
DISPLAY 1.021277 (150 -250);
PAINT ORANGE (150 -250);
DISPLAY INVISIBLE (150 -250);
FORCEADD CAP_A..1
(-225 -450);
FORCEPROP 1 LASTPIN (-225 -550) $PN 2
J 0
(-215 -570);
DISPLAY 0.617021 (-215 -570);
PAINT ORANGE (-215 -570);
FORCEPROP 1 LAST MATERIAL X6S
J 0
(-175 -550);
DISPLAY 0.617021 (-175 -550);
PAINT SKYBLUE (-175 -550);
FORCEPROP 1 LAST PACK_TYPE 0603V
J 0
(-175 -650);
DISPLAY 0.617021 (-175 -650);
PAINT SKYBLUE (-175 -650);
FORCEPROP 1 LASTPIN (-225 -350) $PN 1
J 0
(-215 -370);
DISPLAY 0.617021 (-215 -370);
PAINT ORANGE (-215 -370);
FORCEPROP 1 LAST LOCATION C8T5
J 0
(-175 -350);
DISPLAY 0.617021 (-175 -350);
PAINT AQUA (-175 -350);
FORCEPROP 1 LAST VALUE 22.0UF
J 0
(-175 -400);
DISPLAY 0.617021 (-175 -400);
PAINT SKYBLUE (-175 -400);
FORCEPROP 1 LAST TOLERANCE 20%
J 0
(-175 -500);
DISPLAY 0.617021 (-175 -500);
PAINT SKYBLUE (-175 -500);
FORCEPROP 1 LAST VOLTAGE 4V
J 0
(-175 -450);
DISPLAY 0.617021 (-175 -450);
PAINT SKYBLUE (-175 -450);
FORCEPROP 1 LAST PART_NUMBER E15431-004
J 0
(-175 -600);
DISPLAY 0.617021 (-175 -600);
PAINT BLUE (-175 -600);
FORCEPROP 2 LAST CDS_LIB dev_discrete
J 0
(-225 -450);
PAINT ORANGE (-225 -450);
DISPLAY INVISIBLE (-225 -450);
FORCEPROP 1 LAST PATH I233
J 0
(-175 -300);
DISPLAY 0.978723 (-175 -300);
PAINT WHITE (-175 -300);
DISPLAY INVISIBLE (-175 -300);
FORCEPROP 2 LAST SEC 1
J 0
(-175 -300);
DISPLAY 0.680851 (-175 -300);
PAINT MONO (-175 -300);
DISPLAY INVISIBLE (-175 -300);
FORCEPROP 2 LAST CDS_SEC 1
J 0
(-175 -300);
PAINT ORANGE (-175 -300);
DISPLAY INVISIBLE (-175 -300);
FORCEPROP 2 LAST CDS_LOCATION C8T5
J 0
(-175 -350);
DISPLAY 0.617021 (-175 -350);
PAINT AQUA (-175 -350);
DISPLAY INVISIBLE (-175 -350);
FORCEPROP 0 LAST ROOM PVDDQ_GHJ
J 0
(-175 -250);
DISPLAY 1.021277 (-175 -250);
PAINT ORANGE (-175 -250);
DISPLAY INVISIBLE (-175 -250);
FORCEPROP 2 LAST SEC_TYPE 0603V
J 0
(-175 -250);
DISPLAY 1.021277 (-175 -250);
PAINT ORANGE (-175 -250);
DISPLAY INVISIBLE (-175 -250);
FORCEADD CAP_A..1
(-500 -450);
FORCEPROP 1 LASTPIN (-500 -550) $PN 2
J 0
(-490 -570);
DISPLAY 0.617021 (-490 -570);
PAINT ORANGE (-490 -570);
FORCEPROP 1 LAST MATERIAL X6S
J 0
(-450 -550);
DISPLAY 0.617021 (-450 -550);
PAINT SKYBLUE (-450 -550);
FORCEPROP 1 LAST PACK_TYPE 0603V
J 0
(-450 -650);
DISPLAY 0.617021 (-450 -650);
PAINT SKYBLUE (-450 -650);
FORCEPROP 1 LAST PART_NUMBER E15431-004
J 0
(-450 -600);
DISPLAY 0.617021 (-450 -600);
PAINT BLUE (-450 -600);
FORCEPROP 1 LAST VOLTAGE 4V
J 0
(-450 -450);
DISPLAY 0.617021 (-450 -450);
PAINT SKYBLUE (-450 -450);
FORCEPROP 1 LASTPIN (-500 -350) $PN 1
J 0
(-490 -370);
DISPLAY 0.617021 (-490 -370);
PAINT ORANGE (-490 -370);
FORCEPROP 1 LAST TOLERANCE 20%
J 0
(-450 -500);
DISPLAY 0.617021 (-450 -500);
PAINT SKYBLUE (-450 -500);
FORCEPROP 1 LAST VALUE 22.0UF
J 0
(-450 -400);
DISPLAY 0.617021 (-450 -400);
PAINT SKYBLUE (-450 -400);
FORCEPROP 1 LAST LOCATION C7T5
J 0
(-450 -350);
DISPLAY 0.617021 (-450 -350);
PAINT AQUA (-450 -350);
FORCEPROP 2 LAST CDS_LIB dev_discrete
J 0
(-500 -450);
PAINT ORANGE (-500 -450);
DISPLAY INVISIBLE (-500 -450);
FORCEPROP 1 LAST PATH I234
J 0
(-450 -300);
DISPLAY 0.978723 (-450 -300);
PAINT WHITE (-450 -300);
DISPLAY INVISIBLE (-450 -300);
FORCEPROP 2 LAST SEC 1
J 0
(-450 -300);
DISPLAY 0.680851 (-450 -300);
PAINT MONO (-450 -300);
DISPLAY INVISIBLE (-450 -300);
FORCEPROP 2 LAST CDS_SEC 1
J 0
(-450 -300);
PAINT ORANGE (-450 -300);
DISPLAY INVISIBLE (-450 -300);
FORCEPROP 2 LAST CDS_LOCATION C7T5
J 0
(-450 -350);
DISPLAY 0.617021 (-450 -350);
PAINT AQUA (-450 -350);
DISPLAY INVISIBLE (-450 -350);
FORCEPROP 0 LAST ROOM PVDDQ_GHJ
J 0
(-450 -250);
DISPLAY 1.021277 (-450 -250);
PAINT ORANGE (-450 -250);
DISPLAY INVISIBLE (-450 -250);
FORCEPROP 2 LAST SEC_TYPE 0603V
J 0
(-450 -250);
DISPLAY 1.021277 (-450 -250);
PAINT ORANGE (-450 -250);
DISPLAY INVISIBLE (-450 -250);
FORCEADD CAP_A..1
(-800 -450);
FORCEPROP 1 LASTPIN (-800 -550) $PN 2
J 0
(-790 -570);
DISPLAY 0.617021 (-790 -570);
PAINT ORANGE (-790 -570);
FORCEPROP 1 LAST MATERIAL X6S
J 0
(-750 -550);
DISPLAY 0.617021 (-750 -550);
PAINT SKYBLUE (-750 -550);
FORCEPROP 1 LAST PACK_TYPE 0603V
J 0
(-750 -650);
DISPLAY 0.617021 (-750 -650);
PAINT SKYBLUE (-750 -650);
FORCEPROP 1 LASTPIN (-800 -350) $PN 1
J 0
(-790 -370);
DISPLAY 0.617021 (-790 -370);
PAINT ORANGE (-790 -370);
FORCEPROP 1 LAST LOCATION C7T4
J 0
(-750 -350);
DISPLAY 0.617021 (-750 -350);
PAINT AQUA (-750 -350);
FORCEPROP 1 LAST VALUE 22.0UF
J 0
(-750 -400);
DISPLAY 0.617021 (-750 -400);
PAINT SKYBLUE (-750 -400);
FORCEPROP 1 LAST TOLERANCE 20%
J 0
(-750 -500);
DISPLAY 0.617021 (-750 -500);
PAINT SKYBLUE (-750 -500);
FORCEPROP 1 LAST VOLTAGE 4V
J 0
(-750 -450);
DISPLAY 0.617021 (-750 -450);
PAINT SKYBLUE (-750 -450);
FORCEPROP 1 LAST PART_NUMBER E15431-004
J 0
(-750 -600);
DISPLAY 0.617021 (-750 -600);
PAINT BLUE (-750 -600);
FORCEPROP 2 LAST CDS_LIB dev_discrete
J 0
(-800 -450);
PAINT ORANGE (-800 -450);
DISPLAY INVISIBLE (-800 -450);
FORCEPROP 2 LAST SEC_TYPE 0603V
J 0
(-750 -250);
DISPLAY 1.021277 (-750 -250);
PAINT ORANGE (-750 -250);
DISPLAY INVISIBLE (-750 -250);
FORCEPROP 2 LAST CDS_SEC 1
J 0
(-750 -300);
PAINT ORANGE (-750 -300);
DISPLAY INVISIBLE (-750 -300);
FORCEPROP 2 LAST CDS_LOCATION C7T4
J 0
(-750 -350);
DISPLAY 0.617021 (-750 -350);
PAINT AQUA (-750 -350);
DISPLAY INVISIBLE (-750 -350);
FORCEPROP 0 LAST ROOM PVDDQ_GHJ
J 0
(-750 -250);
DISPLAY 1.021277 (-750 -250);
PAINT ORANGE (-750 -250);
DISPLAY INVISIBLE (-750 -250);
FORCEPROP 1 LAST PATH I235
J 0
(-750 -300);
DISPLAY 0.978723 (-750 -300);
PAINT WHITE (-750 -300);
DISPLAY INVISIBLE (-750 -300);
FORCEPROP 2 LAST SEC 1
J 0
(-750 -300);
DISPLAY 0.680851 (-750 -300);
PAINT MONO (-750 -300);
DISPLAY INVISIBLE (-750 -300);
FORCEADD CAP_A..1
(-1100 -450);
FORCEPROP 1 LASTPIN (-1100 -550) $PN 2
J 0
(-1090 -570);
DISPLAY 0.617021 (-1090 -570);
PAINT ORANGE (-1090 -570);
FORCEPROP 1 LASTPIN (-1100 -350) $PN 1
J 0
(-1090 -370);
DISPLAY 0.617021 (-1090 -370);
PAINT ORANGE (-1090 -370);
FORCEPROP 1 LAST LOCATION C8U3
J 0
(-1050 -350);
DISPLAY 0.617021 (-1050 -350);
PAINT AQUA (-1050 -350);
FORCEPROP 1 LAST PART_NUMBER E15431-004
J 0
(-1050 -600);
DISPLAY 0.617021 (-1050 -600);
PAINT BLUE (-1050 -600);
FORCEPROP 1 LAST VALUE 22.0UF
J 0
(-1050 -400);
DISPLAY 0.617021 (-1050 -400);
PAINT SKYBLUE (-1050 -400);
FORCEPROP 1 LAST TOLERANCE 20%
J 0
(-1050 -500);
DISPLAY 0.617021 (-1050 -500);
PAINT SKYBLUE (-1050 -500);
FORCEPROP 1 LAST PACK_TYPE 0603V
J 0
(-1050 -650);
DISPLAY 0.617021 (-1050 -650);
PAINT SKYBLUE (-1050 -650);
FORCEPROP 1 LAST VOLTAGE 4V
J 0
(-1050 -450);
DISPLAY 0.617021 (-1050 -450);
PAINT SKYBLUE (-1050 -450);
FORCEPROP 1 LAST MATERIAL X6S
J 0
(-1050 -550);
DISPLAY 0.617021 (-1050 -550);
PAINT SKYBLUE (-1050 -550);
FORCEPROP 2 LAST CDS_LIB dev_discrete
J 0
(-1100 -450);
PAINT ORANGE (-1100 -450);
DISPLAY INVISIBLE (-1100 -450);
FORCEPROP 1 LAST PATH I236
J 0
(-1050 -300);
DISPLAY 0.978723 (-1050 -300);
PAINT WHITE (-1050 -300);
DISPLAY INVISIBLE (-1050 -300);
FORCEPROP 2 LAST CDS_SEC 1
J 0
(-1050 -300);
PAINT ORANGE (-1050 -300);
DISPLAY INVISIBLE (-1050 -300);
FORCEPROP 2 LAST CDS_LOCATION C8U3
J 0
(-1050 -350);
DISPLAY 0.617021 (-1050 -350);
PAINT AQUA (-1050 -350);
DISPLAY INVISIBLE (-1050 -350);
FORCEPROP 0 LAST ROOM PVDDQ_ABC
J 0
(-1050 -250);
DISPLAY 1.021277 (-1050 -250);
PAINT ORANGE (-1050 -250);
DISPLAY INVISIBLE (-1050 -250);
FORCEPROP 2 LAST SEC 1
J 0
(-1050 -250);
DISPLAY 0.680851 (-1050 -250);
PAINT MONO (-1050 -250);
DISPLAY INVISIBLE (-1050 -250);
FORCEPROP 2 LAST SEC_TYPE 0603V
J 0
(-1050 -250);
DISPLAY 1.021277 (-1050 -250);
PAINT ORANGE (-1050 -250);
DISPLAY INVISIBLE (-1050 -250);
FORCEADD CAP_A..1
(-1375 -450);
FORCEPROP 1 LASTPIN (-1375 -550) $PN 2
J 0
(-1365 -570);
DISPLAY 0.617021 (-1365 -570);
PAINT ORANGE (-1365 -570);
FORCEPROP 1 LAST MATERIAL X6S
J 0
(-1325 -550);
DISPLAY 0.617021 (-1325 -550);
PAINT SKYBLUE (-1325 -550);
FORCEPROP 1 LAST PACK_TYPE 0603V
J 0
(-1325 -650);
DISPLAY 0.617021 (-1325 -650);
PAINT SKYBLUE (-1325 -650);
FORCEPROP 1 LAST PART_NUMBER E15431-004
J 0
(-1325 -600);
DISPLAY 0.617021 (-1325 -600);
PAINT BLUE (-1325 -600);
FORCEPROP 1 LASTPIN (-1375 -350) $PN 1
J 0
(-1365 -370);
DISPLAY 0.617021 (-1365 -370);
PAINT ORANGE (-1365 -370);
FORCEPROP 1 LAST VOLTAGE 4V
J 0
(-1325 -450);
DISPLAY 0.617021 (-1325 -450);
PAINT SKYBLUE (-1325 -450);
FORCEPROP 1 LAST TOLERANCE 20%
J 0
(-1325 -500);
DISPLAY 0.617021 (-1325 -500);
PAINT SKYBLUE (-1325 -500);
FORCEPROP 1 LAST VALUE 22.0UF
J 0
(-1325 -400);
DISPLAY 0.617021 (-1325 -400);
PAINT SKYBLUE (-1325 -400);
FORCEPROP 1 LAST LOCATION C7U1
J 0
(-1325 -350);
DISPLAY 0.617021 (-1325 -350);
PAINT AQUA (-1325 -350);
FORCEPROP 2 LAST CDS_LIB dev_discrete
J 0
(-1375 -450);
PAINT ORANGE (-1375 -450);
DISPLAY INVISIBLE (-1375 -450);
FORCEPROP 2 LAST SEC 1
J 0
(-1325 -300);
DISPLAY 0.680851 (-1325 -300);
PAINT MONO (-1325 -300);
DISPLAY INVISIBLE (-1325 -300);
FORCEPROP 1 LAST PATH I237
J 0
(-1325 -300);
DISPLAY 0.978723 (-1325 -300);
PAINT WHITE (-1325 -300);
DISPLAY INVISIBLE (-1325 -300);
FORCEPROP 2 LAST CDS_LOCATION C7U1
J 0
(-1325 -350);
DISPLAY 0.617021 (-1325 -350);
PAINT AQUA (-1325 -350);
DISPLAY INVISIBLE (-1325 -350);
FORCEPROP 2 LAST CDS_SEC 1
J 0
(-1325 -300);
PAINT ORANGE (-1325 -300);
DISPLAY INVISIBLE (-1325 -300);
FORCEPROP 0 LAST ROOM PVDDQ_GHJ
J 0
(-1325 -250);
DISPLAY 1.021277 (-1325 -250);
PAINT ORANGE (-1325 -250);
DISPLAY INVISIBLE (-1325 -250);
FORCEPROP 2 LAST SEC_TYPE 0603V
J 0
(-1325 -250);
DISPLAY 1.021277 (-1325 -250);
PAINT ORANGE (-1325 -250);
DISPLAY INVISIBLE (-1325 -250);
FORCEADD CAP_A..1
(-1650 -450);
FORCEPROP 1 LASTPIN (-1650 -550) $PN 2
J 0
(-1640 -570);
DISPLAY 0.617021 (-1640 -570);
PAINT ORANGE (-1640 -570);
FORCEPROP 1 LAST VOLTAGE 4V
J 0
(-1600 -450);
DISPLAY 0.617021 (-1600 -450);
PAINT SKYBLUE (-1600 -450);
FORCEPROP 1 LASTPIN (-1650 -350) $PN 1
J 0
(-1640 -370);
DISPLAY 0.617021 (-1640 -370);
PAINT ORANGE (-1640 -370);
FORCEPROP 1 LAST LOCATION C7U2
J 0
(-1600 -350);
DISPLAY 0.617021 (-1600 -350);
PAINT AQUA (-1600 -350);
FORCEPROP 1 LAST PART_NUMBER E15431-004
J 0
(-1600 -600);
DISPLAY 0.617021 (-1600 -600);
PAINT BLUE (-1600 -600);
FORCEPROP 1 LAST VALUE 22.0UF
J 0
(-1600 -400);
DISPLAY 0.617021 (-1600 -400);
PAINT SKYBLUE (-1600 -400);
FORCEPROP 1 LAST TOLERANCE 20%
J 0
(-1600 -500);
DISPLAY 0.617021 (-1600 -500);
PAINT SKYBLUE (-1600 -500);
FORCEPROP 1 LAST PACK_TYPE 0603V
J 0
(-1600 -650);
DISPLAY 0.617021 (-1600 -650);
PAINT SKYBLUE (-1600 -650);
FORCEPROP 1 LAST MATERIAL X6S
J 0
(-1600 -550);
DISPLAY 0.617021 (-1600 -550);
PAINT SKYBLUE (-1600 -550);
FORCEPROP 2 LAST CDS_LIB dev_discrete
J 0
(-1650 -450);
PAINT ORANGE (-1650 -450);
DISPLAY INVISIBLE (-1650 -450);
FORCEPROP 1 LAST PATH I238
J 0
(-1600 -300);
DISPLAY 0.978723 (-1600 -300);
PAINT WHITE (-1600 -300);
DISPLAY INVISIBLE (-1600 -300);
FORCEPROP 2 LAST SEC 1
J 0
(-1600 -300);
DISPLAY 0.680851 (-1600 -300);
PAINT MONO (-1600 -300);
DISPLAY INVISIBLE (-1600 -300);
FORCEPROP 2 LAST CDS_SEC 1
J 0
(-1600 -300);
PAINT ORANGE (-1600 -300);
DISPLAY INVISIBLE (-1600 -300);
FORCEPROP 2 LAST CDS_LOCATION C7U2
J 0
(-1600 -350);
DISPLAY 0.617021 (-1600 -350);
PAINT AQUA (-1600 -350);
DISPLAY INVISIBLE (-1600 -350);
FORCEPROP 0 LAST ROOM PVDDQ_GHJ
J 0
(-1600 -250);
DISPLAY 1.021277 (-1600 -250);
PAINT ORANGE (-1600 -250);
DISPLAY INVISIBLE (-1600 -250);
FORCEPROP 2 LAST SEC_TYPE 0603V
J 0
(-1600 -250);
DISPLAY 1.021277 (-1600 -250);
PAINT ORANGE (-1600 -250);
DISPLAY INVISIBLE (-1600 -250);
FORCEADD CAP_A..1
(-1950 -450);
FORCEPROP 1 LASTPIN (-1950 -550) $PN 2
J 0
(-1940 -570);
DISPLAY 0.617021 (-1940 -570);
PAINT ORANGE (-1940 -570);
FORCEPROP 1 LAST MATERIAL X6S
J 0
(-1900 -550);
DISPLAY 0.617021 (-1900 -550);
PAINT SKYBLUE (-1900 -550);
FORCEPROP 1 LAST PACK_TYPE 0603V
J 0
(-1900 -650);
DISPLAY 0.617021 (-1900 -650);
PAINT SKYBLUE (-1900 -650);
FORCEPROP 1 LAST PART_NUMBER E15431-004
J 0
(-1900 -600);
DISPLAY 0.617021 (-1900 -600);
PAINT BLUE (-1900 -600);
FORCEPROP 1 LASTPIN (-1950 -350) $PN 1
J 0
(-1940 -370);
DISPLAY 0.617021 (-1940 -370);
PAINT ORANGE (-1940 -370);
FORCEPROP 1 LAST VOLTAGE 4V
J 0
(-1900 -450);
DISPLAY 0.617021 (-1900 -450);
PAINT SKYBLUE (-1900 -450);
FORCEPROP 1 LAST TOLERANCE 20%
J 0
(-1900 -500);
DISPLAY 0.617021 (-1900 -500);
PAINT SKYBLUE (-1900 -500);
FORCEPROP 1 LAST VALUE 22.0UF
J 0
(-1900 -400);
DISPLAY 0.617021 (-1900 -400);
PAINT SKYBLUE (-1900 -400);
FORCEPROP 1 LAST LOCATION C8U2
J 0
(-1900 -350);
DISPLAY 0.617021 (-1900 -350);
PAINT AQUA (-1900 -350);
FORCEPROP 2 LAST CDS_LIB dev_discrete
J 0
(-1950 -450);
PAINT ORANGE (-1950 -450);
DISPLAY INVISIBLE (-1950 -450);
FORCEPROP 2 LAST CDS_SEC 1
J 0
(-1900 -300);
PAINT ORANGE (-1900 -300);
DISPLAY INVISIBLE (-1900 -300);
FORCEPROP 2 LAST CDS_LOCATION C8U2
J 0
(-1900 -350);
DISPLAY 0.617021 (-1900 -350);
PAINT AQUA (-1900 -350);
DISPLAY INVISIBLE (-1900 -350);
FORCEPROP 1 LAST PATH I239
J 0
(-1900 -300);
DISPLAY 0.978723 (-1900 -300);
PAINT WHITE (-1900 -300);
DISPLAY INVISIBLE (-1900 -300);
FORCEPROP 2 LAST SEC 1
J 0
(-1900 -300);
DISPLAY 0.680851 (-1900 -300);
PAINT MONO (-1900 -300);
DISPLAY INVISIBLE (-1900 -300);
FORCEPROP 0 LAST ROOM PVDDQ_GHJ
J 0
(-1900 -250);
DISPLAY 1.021277 (-1900 -250);
PAINT ORANGE (-1900 -250);
DISPLAY INVISIBLE (-1900 -250);
FORCEPROP 2 LAST SEC_TYPE 0603V
J 0
(-1900 -250);
DISPLAY 1.021277 (-1900 -250);
PAINT ORANGE (-1900 -250);
DISPLAY INVISIBLE (-1900 -250);
FORCEADD PVDDQ_GHJ..1
(-2250 -200);
FORCEPROP 3 LASTPIN (-2250 -250) SIG_NAME PVDDQ_GHJ\g
J 0
(-2240 -240);
DISPLAY 0.659574 (-2240 -240);
PAINT MONO (-2240 -240);
DISPLAY INVISIBLE (-2240 -240);
FORCEPROP 1 LAST VOLTAGE 1.2V
J 0
(-2295 -243);
DISPLAY 0.340426 (-2295 -243);
PAINT SKYBLUE (-2295 -243);
DISPLAY INVISIBLE (-2295 -243);
FORCEPROP 2 LAST CDS_LIB mstr_symbols
J 0
(-2250 -200);
PAINT ORANGE (-2250 -200);
DISPLAY INVISIBLE (-2250 -200);
FORCEPROP 1 LAST BODY_TYPE PLUMBING
J 0
(-2295 -243);
DISPLAY 0.340426 (-2295 -243);
PAINT GREEN (-2295 -243);
DISPLAY INVISIBLE (-2295 -243);
FORCEPROP 1 LAST PATH I240
J 0
(-2200 -175);
DISPLAY 0.872340 (-2200 -175);
PAINT AQUA (-2200 -175);
DISPLAY INVISIBLE (-2200 -175);
FORCEPROP 1 LAST HDL_POWER PVDDQ_GHJ
J 1
(-2250 -150);
DISPLAY 0.872340 (-2250 -150);
PAINT GREEN (-2250 -150);
DISPLAY INVISIBLE (-2250 -150);
FORCEADD CAP_A..1
(-2250 -450);
FORCEPROP 1 LASTPIN (-2250 -550) $PN 2
J 0
(-2240 -570);
DISPLAY 0.617021 (-2240 -570);
PAINT ORANGE (-2240 -570);
FORCEPROP 1 LAST MATERIAL X6S
J 0
(-2200 -550);
DISPLAY 0.617021 (-2200 -550);
PAINT SKYBLUE (-2200 -550);
FORCEPROP 1 LAST PACK_TYPE 0603V
J 0
(-2200 -650);
DISPLAY 0.617021 (-2200 -650);
PAINT SKYBLUE (-2200 -650);
FORCEPROP 1 LASTPIN (-2250 -350) $PN 1
J 0
(-2240 -370);
DISPLAY 0.617021 (-2240 -370);
PAINT ORANGE (-2240 -370);
FORCEPROP 1 LAST VOLTAGE 4V
J 0
(-2200 -450);
DISPLAY 0.617021 (-2200 -450);
PAINT SKYBLUE (-2200 -450);
FORCEPROP 1 LAST TOLERANCE 20%
J 0
(-2200 -500);
DISPLAY 0.617021 (-2200 -500);
PAINT SKYBLUE (-2200 -500);
FORCEPROP 1 LAST LOCATION C8U7
J 0
(-2200 -350);
DISPLAY 0.617021 (-2200 -350);
PAINT AQUA (-2200 -350);
FORCEPROP 1 LAST PART_NUMBER E15431-004
J 0
(-2200 -600);
DISPLAY 0.617021 (-2200 -600);
PAINT BLUE (-2200 -600);
FORCEPROP 1 LAST VALUE 22.0UF
J 0
(-2200 -400);
DISPLAY 0.617021 (-2200 -400);
PAINT SKYBLUE (-2200 -400);
FORCEPROP 2 LAST CDS_LIB dev_discrete
J 0
(-2250 -450);
PAINT ORANGE (-2250 -450);
DISPLAY INVISIBLE (-2250 -450);
FORCEPROP 2 LAST CDS_LOCATION C8U7
J 0
(-2200 -350);
DISPLAY 0.617021 (-2200 -350);
PAINT AQUA (-2200 -350);
DISPLAY INVISIBLE (-2200 -350);
FORCEPROP 2 LAST CDS_SEC 1
J 0
(-2200 -300);
PAINT ORANGE (-2200 -300);
DISPLAY INVISIBLE (-2200 -300);
FORCEPROP 1 LAST PATH I241
J 0
(-2200 -300);
DISPLAY 0.978723 (-2200 -300);
PAINT WHITE (-2200 -300);
DISPLAY INVISIBLE (-2200 -300);
FORCEPROP 2 LAST SEC_TYPE 0603V
J 0
(-2200 -250);
DISPLAY 1.021277 (-2200 -250);
PAINT ORANGE (-2200 -250);
DISPLAY INVISIBLE (-2200 -250);
FORCEPROP 2 LAST SEC 1
J 0
(-2200 -250);
DISPLAY 0.680851 (-2200 -250);
PAINT MONO (-2200 -250);
DISPLAY INVISIBLE (-2200 -250);
FORCEPROP 0 LAST ROOM PVDDQ_GHJ
J 0
(-2200 -250);
DISPLAY 1.021277 (-2200 -250);
PAINT ORANGE (-2200 -250);
DISPLAY INVISIBLE (-2200 -250);
FORCEADD GND..1
(-2250 -725);
FORCEPROP 3 LASTPIN (-2250 -675) SIG_NAME GND\g
J 0
(-2240 -665);
DISPLAY 0.659574 (-2240 -665);
PAINT MONO (-2240 -665);
DISPLAY INVISIBLE (-2240 -665);
FORCEPROP 2 LAST BOM_COST PROC_VRD_VCCIN_CPU0
J 0
(-2625 -650);
DISPLAY 1.446809 (-2625 -650);
PAINT MONO (-2625 -650);
DISPLAY INVISIBLE (-2625 -650);
FORCEPROP 2 LAST ROOM VDDQ_ABC_PWR_VR
J 0
(-2800 -650);
DISPLAY 1.936170 (-2800 -650);
PAINT ORANGE (-2800 -650);
DISPLAY INVISIBLE (-2800 -650);
FORCEPROP 1 LAST SIZE 1B
J 0
(-2175 -775);
DISPLAY 1.723404 (-2175 -775);
PAINT GREEN (-2175 -775);
DISPLAY INVISIBLE (-2175 -775);
FORCEPROP 1 LAST BODY_TYPE PLUMBING
J 0
(-2295 -768);
DISPLAY 0.340426 (-2295 -768);
PAINT GREEN (-2295 -768);
DISPLAY INVISIBLE (-2295 -768);
FORCEPROP 1 LAST VOLTAGE 0
J 0
(-2250 -725);
PAINT SKYBLUE (-2250 -725);
DISPLAY INVISIBLE (-2250 -725);
FORCEPROP 2 LAST CDS_LIB mstr_symbols
J 0
(-2250 -725);
PAINT ORANGE (-2250 -725);
DISPLAY INVISIBLE (-2250 -725);
FORCEPROP 1 LAST PATH I242
J 0
(-2175 -725);
DISPLAY 0.872340 (-2175 -725);
PAINT AQUA (-2175 -725);
DISPLAY INVISIBLE (-2175 -725);
FORCEPROP 1 LAST HDL_POWER GND
J 0
(-2250 -575);
DISPLAY 1.723404 (-2250 -575);
PAINT GREEN (-2250 -575);
DISPLAY INVISIBLE (-2250 -575);
FORCEADD SHUNT..1
(-250 2325);
FORCEPROP 1 LASTPIN (-400 2325) $PN 1
J 2
(-350 2335);
DISPLAY 0.617021 (-350 2335);
PAINT ORANGE (-350 2335);
FORCEPROP 1 LAST LOCATION SH7U1
J 0
(-325 2375);
DISPLAY 0.617021 (-325 2375);
PAINT AQUA (-325 2375);
FORCEPROP 1 LAST PART_NUMBER N_A
J 0
(-325 2235);
DISPLAY 0.617021 (-325 2235);
PAINT BLUE (-325 2235);
FORCEPROP 1 LASTPIN (-100 2325) $PN 2
J 0
(-140 2335);
DISPLAY 0.617021 (-140 2335);
PAINT ORANGE (-140 2335);
FORCEPROP 1 LAST PIN_SHORT A:B
J 0
(-325 2075);
DISPLAY 1.021277 (-325 2075);
PAINT ORANGE (-325 2075);
DISPLAY INVISIBLE (-325 2075);
FORCEPROP 1 LAST PACK_TYPE SH0201
J 0
(-310 2140);
DISPLAY 0.978723 (-310 2140);
PAINT SKYBLUE (-310 2140);
DISPLAY INVISIBLE (-310 2140);
FORCEPROP 1 LAST MATERIAL EMPTY
J 0
(-325 2190);
DISPLAY 0.978723 (-325 2190);
PAINT RED (-325 2190);
DISPLAY INVISIBLE (-325 2190);
FORCEPROP 0 LAST SEC 1
J 0
(-325 2425);
DISPLAY 0.680851 (-325 2425);
PAINT MONO (-325 2425);
DISPLAY INVISIBLE (-325 2425);
FORCEPROP 1 LAST PATH I243
J 0
(-300 2425);
DISPLAY 0.978723 (-300 2425);
PAINT ORANGE (-300 2425);
DISPLAY INVISIBLE (-300 2425);
FORCEPROP 2 LAST SEC_TYPE SH0201
J 0
(-300 2475);
DISPLAY 1.021277 (-300 2475);
PAINT ORANGE (-300 2475);
DISPLAY INVISIBLE (-300 2475);
FORCEPROP 2 LAST CDS_LIB mstr_misc
J 0
(-250 2325);
PAINT ORANGE (-250 2325);
DISPLAY INVISIBLE (-250 2325);
FORCEADD SHUNT..1
(-275 1875);
FORCEPROP 1 LAST PART_NUMBER N_A
J 0
(-350 1785);
DISPLAY 0.617021 (-350 1785);
PAINT BLUE (-350 1785);
FORCEPROP 1 LASTPIN (-425 1875) $PN 1
J 2
(-375 1885);
DISPLAY 0.617021 (-375 1885);
PAINT ORANGE (-375 1885);
FORCEPROP 1 LAST LOCATION SH7U2
J 0
(-350 1925);
DISPLAY 0.617021 (-350 1925);
PAINT AQUA (-350 1925);
FORCEPROP 1 LASTPIN (-125 1875) $PN 2
J 0
(-165 1885);
DISPLAY 0.617021 (-165 1885);
PAINT ORANGE (-165 1885);
FORCEPROP 1 LAST MATERIAL EMPTY
J 0
(-350 1740);
DISPLAY 0.978723 (-350 1740);
PAINT RED (-350 1740);
DISPLAY INVISIBLE (-350 1740);
FORCEPROP 1 LAST PACK_TYPE SH0201
J 0
(-335 1690);
DISPLAY 0.978723 (-335 1690);
PAINT SKYBLUE (-335 1690);
DISPLAY INVISIBLE (-335 1690);
FORCEPROP 1 LAST PIN_SHORT A:B
J 0
(-350 1625);
DISPLAY 1.021277 (-350 1625);
PAINT ORANGE (-350 1625);
DISPLAY INVISIBLE (-350 1625);
FORCEPROP 2 LAST CDS_LIB mstr_misc
J 0
(-275 1875);
PAINT ORANGE (-275 1875);
DISPLAY INVISIBLE (-275 1875);
FORCEPROP 0 LAST SEC 1
J 0
(-350 1975);
DISPLAY 0.680851 (-350 1975);
PAINT MONO (-350 1975);
DISPLAY INVISIBLE (-350 1975);
FORCEPROP 1 LAST PATH I244
J 0
(-325 1975);
DISPLAY 0.978723 (-325 1975);
PAINT ORANGE (-325 1975);
DISPLAY INVISIBLE (-325 1975);
FORCEPROP 2 LAST SEC_TYPE SH0201
J 0
(-325 2025);
DISPLAY 1.021277 (-325 2025);
PAINT ORANGE (-325 2025);
DISPLAY INVISIBLE (-325 2025);
FORCEADD RES..2
(4325 -75);
FORCEPROP 1 LASTPIN (4325 -175) $PN 2
J 0
(4330 -165);
DISPLAY 0.617021 (4330 -165);
PAINT GREEN (4330 -165);
FORCEPROP 1 LAST WATTAGE 1/10W
J 0
(4365 -100);
DISPLAY 0.617021 (4365 -100);
PAINT SKYBLUE (4365 -100);
FORCEPROP 1 LAST MATERIAL CHIP
J 0
(4365 -150);
DISPLAY 0.617021 (4365 -150);
PAINT SKYBLUE (4365 -150);
FORCEPROP 1 LAST PACK_TYPE 0603
J 0
(4365 -250);
DISPLAY 0.617021 (4365 -250);
PAINT SKYBLUE (4365 -250);
FORCEPROP 1 LAST TOLERANCE 1%
J 0
(4370 -50);
DISPLAY 0.617021 (4370 -50);
PAINT SKYBLUE (4370 -50);
FORCEPROP 1 LAST PART_NUMBER G22026-003
J 0
(4365 -200);
DISPLAY 0.617021 (4365 -200);
PAINT BLUE (4365 -200);
FORCEPROP 1 LAST VALUE 120.0
J 0
(4370 0);
DISPLAY 0.617021 (4370 0);
PAINT SKYBLUE (4370 0);
FORCEPROP 1 LASTPIN (4325 25) $PN 1
J 0
(4330 -13);
DISPLAY 0.617021 (4330 -13);
PAINT GREEN (4330 -13);
FORCEPROP 1 LAST LOCATION R1G20
J 0
(4370 50);
DISPLAY 0.617021 (4370 50);
PAINT AQUA (4370 50);
FORCEPROP 2 LAST CDS_LIB mstr_discrete
J 0
(4325 -75);
PAINT ORANGE (4325 -75);
DISPLAY INVISIBLE (4325 -75);
FORCEPROP 2 LAST BOM_COST MEM_VRD_PVPP_AB
J 0
(4375 100);
PAINT MONO (4375 100);
DISPLAY INVISIBLE (4375 100);
FORCEPROP 2 LAST CDS_SEC 1
J 0
(4375 150);
PAINT MONO (4375 150);
DISPLAY INVISIBLE (4375 150);
FORCEPROP 2 LAST $SEC 1
J 0
(4375 150);
PAINT MONO (4375 150);
DISPLAY INVISIBLE (4375 150);
FORCEPROP 2 LAST CDS_LOCATION R1G20
J 0
(4370 50);
DISPLAY 0.617021 (4370 50);
PAINT AQUA (4370 50);
DISPLAY INVISIBLE (4370 50);
FORCEPROP 1 LAST PATH I58
J 0
(4375 100);
DISPLAY 0.978723 (4375 100);
PAINT GREEN (4375 100);
DISPLAY INVISIBLE (4375 100);
FORCEPROP 2 LAST ROOM VDDQ_GHJ_PWR_VR
J 0
(4375 100);
PAINT MONO (4375 100);
DISPLAY INVISIBLE (4375 100);
FORCEADD GND..1
(100 1750);
FORCEPROP 3 LASTPIN (100 1800) SIG_NAME GND\g
J 0
(110 1810);
DISPLAY 0.659574 (110 1810);
PAINT MONO (110 1810);
DISPLAY INVISIBLE (110 1810);
FORCEPROP 2 LAST ROOM VDDQ_GHJ_PWR_VR
J 0
(-450 1825);
PAINT ORANGE (-450 1825);
DISPLAY INVISIBLE (-450 1825);
FORCEPROP 2 LAST BOM_COST MEM_VRD_PVPP_AB
J 0
(-225 1825);
PAINT MONO (-225 1825);
DISPLAY INVISIBLE (-225 1825);
FORCEPROP 1 LAST VOLTAGE 0
J 0
(100 1750);
PAINT SKYBLUE (100 1750);
DISPLAY INVISIBLE (100 1750);
FORCEPROP 2 LAST CDS_LIB mstr_symbols
J 0
(100 1750);
PAINT ORANGE (100 1750);
DISPLAY INVISIBLE (100 1750);
FORCEPROP 1 LAST SIZE 1B
J 0
(175 1700);
DISPLAY 0.893617 (175 1700);
PAINT GREEN (175 1700);
DISPLAY INVISIBLE (175 1700);
FORCEPROP 1 LAST BODY_TYPE PLUMBING
J 0
(55 1707);
DISPLAY 0.340426 (55 1707);
PAINT GREEN (55 1707);
DISPLAY INVISIBLE (55 1707);
FORCEPROP 1 LAST PATH I65
J 0
(175 1750);
DISPLAY 1.170213 (175 1750);
PAINT AQUA (175 1750);
DISPLAY INVISIBLE (175 1750);
FORCEPROP 1 LAST HDL_POWER GND
J 0
(100 1900);
DISPLAY 0.893617 (100 1900);
PAINT GREEN (100 1900);
DISPLAY INVISIBLE (100 1900);
FORCEADD OFFPAGE..1
(-1925 2050);
FORCEPROP 2 LAST $XR0 223 
J 0
(-2177 2050);
DISPLAY 0.638298 (-2177 2050);
PAINT MONO (-2177 2050);
FORCEPROP 2 LAST BOM_COST MEM_VRD_PVPP_AB
J 0
(-2200 2100);
PAINT MONO (-2200 2100);
DISPLAY INVISIBLE (-2200 2100);
FORCEPROP 1 LAST COMMENT_BODY TRUE
J 0
(-1800 1950);
DISPLAY 0.893617 (-1800 1950);
PAINT GREEN (-1800 1950);
DISPLAY INVISIBLE (-1800 1950);
FORCEPROP 1 LAST OFFPAGE TRUE
J 0
(-1600 1925);
DISPLAY 0.893617 (-1600 1925);
PAINT GREEN (-1600 1925);
DISPLAY INVISIBLE (-1600 1925);
FORCEPROP 2 LAST CDS_LIB mstr_standard
J 0
(-1925 2050);
PAINT ORANGE (-1925 2050);
DISPLAY INVISIBLE (-1925 2050);
FORCEPROP 2 LAST PATH I70
J 0
(-1855 2120);
DISPLAY 1.361702 (-1855 2120);
PAINT ORANGE (-1855 2120);
DISPLAY INVISIBLE (-1855 2120);
FORCEADD OFFPAGE..1
(-1925 2300);
FORCEPROP 2 LAST $XR0 223 
J 0
(-2177 2300);
DISPLAY 0.638298 (-2177 2300);
PAINT MONO (-2177 2300);
FORCEPROP 1 LAST COMMENT_BODY TRUE
J 0
(-1800 2200);
DISPLAY 1.170213 (-1800 2200);
PAINT GREEN (-1800 2200);
DISPLAY INVISIBLE (-1800 2200);
FORCEPROP 2 LAST CDS_LIB mstr_standard
J 0
(-1925 2300);
PAINT ORANGE (-1925 2300);
DISPLAY INVISIBLE (-1925 2300);
FORCEPROP 2 LAST PATH I72
J 0
(-1875 2375);
DISPLAY 1.361702 (-1875 2375);
PAINT ORANGE (-1875 2375);
DISPLAY INVISIBLE (-1875 2375);
FORCEPROP 1 LAST OFFPAGE TRUE
J 0
(-1600 2175);
DISPLAY 1.170213 (-1600 2175);
PAINT GREEN (-1600 2175);
DISPLAY INVISIBLE (-1600 2175);
FORCEADD PVDDQ_GHJ..1
(100 2450);
FORCEPROP 3 LASTPIN (100 2400) SIG_NAME PVDDQ_GHJ\g
J 0
(110 2410);
DISPLAY 0.659574 (110 2410);
PAINT MONO (110 2410);
DISPLAY INVISIBLE (110 2410);
FORCEPROP 1 LAST VOLTAGE 1.2V
J 0
(55 2407);
DISPLAY 0.340426 (55 2407);
PAINT SKYBLUE (55 2407);
DISPLAY INVISIBLE (55 2407);
FORCEPROP 2 LAST CDS_LIB mstr_symbols
J 0
(100 2450);
PAINT ORANGE (100 2450);
DISPLAY INVISIBLE (100 2450);
FORCEPROP 1 LAST BODY_TYPE PLUMBING
J 0
(55 2407);
DISPLAY 0.340426 (55 2407);
PAINT GREEN (55 2407);
DISPLAY INVISIBLE (55 2407);
FORCEPROP 1 LAST PATH I73
J 0
(150 2475);
DISPLAY 0.872340 (150 2475);
PAINT AQUA (150 2475);
DISPLAY INVISIBLE (150 2475);
FORCEPROP 1 LAST HDL_POWER PVDDQ_GHJ
J 1
(100 2500);
DISPLAY 0.872340 (100 2500);
PAINT GREEN (100 2500);
DISPLAY INVISIBLE (100 2500);
FORCEPROP 2 LAST BOM_COST MEM_VRD_PVPP_AB
J 0
(125 2550);
PAINT MONO (125 2550);
DISPLAY INVISIBLE (125 2550);
FORCEPROP 2 LAST ROOM VDDQ_GHJ_PWR_VR
J 0
(350 2550);
PAINT ORANGE (350 2550);
DISPLAY INVISIBLE (350 2550);
FORCEADD RES..2
(-650 2075);
FORCEPROP 1 LASTPIN (-650 1975) $PN 2
J 0
(-645 1985);
DISPLAY 0.617021 (-645 1985);
PAINT ORANGE (-645 1985);
FORCEPROP 1 LAST MATERIAL EMPTY
J 0
(-610 2000);
DISPLAY 0.617021 (-610 2000);
PAINT RED (-610 2000);
FORCEPROP 1 LAST PACK_TYPE 0402
J 0
(-610 1900);
DISPLAY 0.617021 (-610 1900);
PAINT SKYBLUE (-610 1900);
FORCEPROP 1 LASTPIN (-650 2175) $PN 1
J 0
(-645 2137);
DISPLAY 0.617021 (-645 2137);
PAINT ORANGE (-645 2137);
FORCEPROP 1 LAST TOLERANCE 1%
J 0
(-605 2100);
DISPLAY 0.617021 (-605 2100);
PAINT SKYBLUE (-605 2100);
FORCEPROP 1 LAST LOCATION R7U2
J 0
(-605 2200);
DISPLAY 0.617021 (-605 2200);
PAINT AQUA (-605 2200);
FORCEPROP 1 LAST PART_NUMBER G21796-017
J 0
(-610 1950);
DISPLAY 0.617021 (-610 1950);
PAINT BLUE (-610 1950);
FORCEPROP 1 LAST WATTAGE 1/16W
J 0
(-610 2050);
DISPLAY 0.617021 (-610 2050);
PAINT SKYBLUE (-610 2050);
FORCEPROP 1 LAST VALUE 100.0
J 0
(-605 2150);
DISPLAY 0.617021 (-605 2150);
PAINT SKYBLUE (-605 2150);
FORCEPROP 2 LAST CDS_LIB mstr_discrete
J 0
(-650 2075);
PAINT ORANGE (-650 2075);
DISPLAY INVISIBLE (-650 2075);
FORCEPROP 2 LAST CDS_LOCATION R7U2
J 0
(-605 2200);
DISPLAY 0.617021 (-605 2200);
PAINT AQUA (-605 2200);
DISPLAY INVISIBLE (-605 2200);
FORCEPROP 0 LAST ROOM VDDQ_GHJ_PWR_VR
J 0
(-600 2250);
DISPLAY 1.021277 (-600 2250);
PAINT ORANGE (-600 2250);
DISPLAY INVISIBLE (-600 2250);
FORCEPROP 1 LAST PATH I74
J 0
(-600 2250);
DISPLAY 1.319149 (-600 2250);
PAINT WHITE (-600 2250);
DISPLAY INVISIBLE (-600 2250);
FORCEPROP 2 LAST SEC_TYPE 0402
J 0
(-600 2325);
DISPLAY 1.021277 (-600 2325);
PAINT ORANGE (-600 2325);
DISPLAY INVISIBLE (-600 2325);
FORCEPROP 2 LAST SEC 1
J 0
(-600 2325);
DISPLAY 0.680851 (-600 2325);
PAINT MONO (-600 2325);
DISPLAY INVISIBLE (-600 2325);
FORCEADD CAPP..1
(2700 -75);
FORCEPROP 1 LASTPIN (2700 -175) $PN 2
J 0
(2710 -190);
DISPLAY 0.617021 (2710 -190);
PAINT ORANGE (2710 -190);
FORCEPROP 1 LAST PART_NUMBER 699013-049
J 0
(2750 -275);
DISPLAY 0.617021 (2750 -275);
PAINT BLUE (2750 -275);
FORCEPROP 1 LAST TOLERANCE 20%
J 0
(2750 -75);
DISPLAY 0.617021 (2750 -75);
PAINT SKYBLUE (2750 -75);
FORCEPROP 1 LAST PACK_TYPE 3018
J 0
(2750 -225);
DISPLAY 0.617021 (2750 -225);
PAINT SKYBLUE (2750 -225);
FORCEPROP 1 LAST VOLTAGE 2.5V
J 0
(2750 -125);
DISPLAY 0.617021 (2750 -125);
PAINT SKYBLUE (2750 -125);
FORCEPROP 1 LAST MATERIAL ALUM
J 0
(2750 -175);
DISPLAY 0.617021 (2750 -175);
PAINT SKYBLUE (2750 -175);
FORCEPROP 1 LAST VALUE 470UF
J 0
(2750 -25);
DISPLAY 0.617021 (2750 -25);
PAINT SKYBLUE (2750 -25);
FORCEPROP 1 LASTPIN (2700 25) $PN 1
J 0
(2710 10);
DISPLAY 0.617021 (2710 10);
PAINT ORANGE (2710 10);
FORCEPROP 1 LAST LOCATION C9T5
J 0
(2750 25);
DISPLAY 0.617021 (2750 25);
PAINT AQUA (2750 25);
FORCEPROP 2 LAST CDS_LIB mstr_discrete
J 0
(2700 -75);
PAINT ORANGE (2700 -75);
DISPLAY INVISIBLE (2700 -75);
FORCEPROP 2 LAST CDS_LOCATION C9T5
J 0
(2750 25);
DISPLAY 0.617021 (2750 25);
PAINT AQUA (2750 25);
DISPLAY INVISIBLE (2750 25);
FORCEPROP 0 LAST ROOM VDDQ_GHJ_PWR_VR
J 0
(2750 75);
DISPLAY 1.021277 (2750 75);
PAINT ORANGE (2750 75);
DISPLAY INVISIBLE (2750 75);
FORCEPROP 1 LAST PATH I75
J 0
(2750 75);
DISPLAY 1.319149 (2750 75);
PAINT ORANGE (2750 75);
DISPLAY INVISIBLE (2750 75);
FORCEPROP 2 LAST SEC 1
J 0
(2750 150);
DISPLAY 0.680851 (2750 150);
PAINT MONO (2750 150);
DISPLAY INVISIBLE (2750 150);
FORCEPROP 2 LAST SEC_TYPE 3018
J 0
(2750 150);
DISPLAY 1.021277 (2750 150);
PAINT ORANGE (2750 150);
DISPLAY INVISIBLE (2750 150);
FORCEADD CAPP..1
(3125 -75);
FORCEPROP 1 LASTPIN (3125 -175) $PN 2
J 0
(3135 -190);
DISPLAY 0.617021 (3135 -190);
PAINT ORANGE (3135 -190);
FORCEPROP 1 LAST TOLERANCE 20%
J 0
(3175 -75);
DISPLAY 0.617021 (3175 -75);
PAINT SKYBLUE (3175 -75);
FORCEPROP 1 LAST PACK_TYPE 3018
J 0
(3175 -225);
DISPLAY 0.617021 (3175 -225);
PAINT SKYBLUE (3175 -225);
FORCEPROP 1 LAST VOLTAGE 2.5V
J 0
(3175 -125);
DISPLAY 0.617021 (3175 -125);
PAINT SKYBLUE (3175 -125);
FORCEPROP 1 LAST MATERIAL ALUM
J 0
(3175 -175);
DISPLAY 0.617021 (3175 -175);
PAINT SKYBLUE (3175 -175);
FORCEPROP 1 LAST PART_NUMBER 699013-049
J 0
(3175 -275);
DISPLAY 0.617021 (3175 -275);
PAINT BLUE (3175 -275);
FORCEPROP 1 LAST VALUE 470UF
J 0
(3175 -25);
DISPLAY 0.617021 (3175 -25);
PAINT SKYBLUE (3175 -25);
FORCEPROP 1 LASTPIN (3125 25) $PN 1
J 0
(3135 10);
DISPLAY 0.617021 (3135 10);
PAINT ORANGE (3135 10);
FORCEPROP 1 LAST LOCATION C9U2
J 0
(3175 25);
DISPLAY 0.617021 (3175 25);
PAINT AQUA (3175 25);
FORCEPROP 2 LAST CDS_LIB mstr_discrete
J 0
(3125 -75);
PAINT ORANGE (3125 -75);
DISPLAY INVISIBLE (3125 -75);
FORCEPROP 0 LAST ROOM VDDQ_GHJ_PWR_VR
J 0
(3175 75);
DISPLAY 1.021277 (3175 75);
PAINT ORANGE (3175 75);
DISPLAY INVISIBLE (3175 75);
FORCEPROP 1 LAST PATH I76
J 0
(3175 75);
DISPLAY 1.319149 (3175 75);
PAINT ORANGE (3175 75);
DISPLAY INVISIBLE (3175 75);
FORCEPROP 2 LAST CDS_LOCATION C9U2
J 0
(3175 25);
DISPLAY 0.617021 (3175 25);
PAINT AQUA (3175 25);
DISPLAY INVISIBLE (3175 25);
FORCEPROP 2 LAST SEC 1
J 0
(3175 150);
DISPLAY 0.680851 (3175 150);
PAINT MONO (3175 150);
DISPLAY INVISIBLE (3175 150);
FORCEPROP 2 LAST SEC_TYPE 3018
J 0
(3175 150);
DISPLAY 1.021277 (3175 150);
PAINT ORANGE (3175 150);
DISPLAY INVISIBLE (3175 150);
FORCEADD CAPP..1
(3550 -75);
FORCEPROP 1 LASTPIN (3550 -175) $PN 2
J 0
(3560 -190);
DISPLAY 0.617021 (3560 -190);
PAINT ORANGE (3560 -190);
FORCEPROP 1 LAST TOLERANCE 20%
J 0
(3600 -75);
DISPLAY 0.617021 (3600 -75);
PAINT SKYBLUE (3600 -75);
FORCEPROP 1 LAST PACK_TYPE 3018
J 0
(3600 -225);
DISPLAY 0.617021 (3600 -225);
PAINT SKYBLUE (3600 -225);
FORCEPROP 1 LAST VOLTAGE 2.5V
J 0
(3600 -125);
DISPLAY 0.617021 (3600 -125);
PAINT SKYBLUE (3600 -125);
FORCEPROP 1 LAST MATERIAL ALUM
J 0
(3600 -175);
DISPLAY 0.617021 (3600 -175);
PAINT SKYBLUE (3600 -175);
FORCEPROP 1 LAST PART_NUMBER 699013-049
J 0
(3600 -275);
DISPLAY 0.617021 (3600 -275);
PAINT BLUE (3600 -275);
FORCEPROP 1 LAST VALUE 470UF
J 0
(3600 -25);
DISPLAY 0.617021 (3600 -25);
PAINT SKYBLUE (3600 -25);
FORCEPROP 1 LASTPIN (3550 25) $PN 1
J 0
(3560 10);
DISPLAY 0.617021 (3560 10);
PAINT ORANGE (3560 10);
FORCEPROP 1 LAST LOCATION C9U9
J 0
(3600 25);
DISPLAY 0.617021 (3600 25);
PAINT AQUA (3600 25);
FORCEPROP 2 LAST CDS_LIB mstr_discrete
J 0
(3550 -75);
PAINT ORANGE (3550 -75);
DISPLAY INVISIBLE (3550 -75);
FORCEPROP 2 LAST SEC_TYPE 3018
J 0
(3600 150);
DISPLAY 1.021277 (3600 150);
PAINT ORANGE (3600 150);
DISPLAY INVISIBLE (3600 150);
FORCEPROP 2 LAST SEC 1
J 0
(3600 150);
DISPLAY 0.680851 (3600 150);
PAINT MONO (3600 150);
DISPLAY INVISIBLE (3600 150);
FORCEPROP 2 LAST CDS_LOCATION C9U9
J 0
(3600 25);
DISPLAY 0.617021 (3600 25);
PAINT AQUA (3600 25);
DISPLAY INVISIBLE (3600 25);
FORCEPROP 1 LAST PATH I77
J 0
(3600 75);
DISPLAY 1.319149 (3600 75);
PAINT ORANGE (3600 75);
DISPLAY INVISIBLE (3600 75);
FORCEPROP 0 LAST ROOM VDDQ_GHJ_PWR_VR
J 0
(3600 75);
DISPLAY 1.021277 (3600 75);
PAINT ORANGE (3600 75);
DISPLAY INVISIBLE (3600 75);
FORCEADD CAPP..1
(3950 -100);
FORCEPROP 1 LASTPIN (3950 -200) $PN 2
J 0
(3960 -215);
DISPLAY 0.617021 (3960 -215);
PAINT ORANGE (3960 -215);
FORCEPROP 1 LAST TOLERANCE 20%
J 0
(4000 -100);
DISPLAY 0.617021 (4000 -100);
PAINT SKYBLUE (4000 -100);
FORCEPROP 1 LAST PART_NUMBER 699013-049
J 0
(4000 -300);
DISPLAY 0.617021 (4000 -300);
PAINT BLUE (4000 -300);
FORCEPROP 1 LAST VALUE 470UF
J 0
(4000 -50);
DISPLAY 0.617021 (4000 -50);
PAINT SKYBLUE (4000 -50);
FORCEPROP 1 LAST PACK_TYPE 3018
J 0
(4000 -250);
DISPLAY 0.617021 (4000 -250);
PAINT SKYBLUE (4000 -250);
FORCEPROP 1 LAST VOLTAGE 2.5V
J 0
(4000 -150);
DISPLAY 0.617021 (4000 -150);
PAINT SKYBLUE (4000 -150);
FORCEPROP 1 LAST MATERIAL ALUM
J 0
(4000 -200);
DISPLAY 0.617021 (4000 -200);
PAINT SKYBLUE (4000 -200);
FORCEPROP 1 LAST LOCATION C9U5
J 0
(4000 0);
DISPLAY 0.617021 (4000 0);
PAINT AQUA (4000 0);
FORCEPROP 1 LASTPIN (3950 0) $PN 1
J 0
(3960 -15);
DISPLAY 0.617021 (3960 -15);
PAINT ORANGE (3960 -15);
FORCEPROP 2 LAST CDS_LIB mstr_discrete
J 0
(3950 -100);
PAINT ORANGE (3950 -100);
DISPLAY INVISIBLE (3950 -100);
FORCEPROP 2 LAST CDS_LOCATION C9U5
J 0
(4000 0);
DISPLAY 0.617021 (4000 0);
PAINT AQUA (4000 0);
DISPLAY INVISIBLE (4000 0);
FORCEPROP 2 LAST SEC_TYPE 3018
J 0
(4000 125);
DISPLAY 1.021277 (4000 125);
PAINT ORANGE (4000 125);
DISPLAY INVISIBLE (4000 125);
FORCEPROP 2 LAST SEC 1
J 0
(4000 125);
DISPLAY 0.680851 (4000 125);
PAINT MONO (4000 125);
DISPLAY INVISIBLE (4000 125);
FORCEPROP 1 LAST PATH I78
J 0
(4000 50);
DISPLAY 1.319149 (4000 50);
PAINT ORANGE (4000 50);
DISPLAY INVISIBLE (4000 50);
FORCEPROP 0 LAST ROOM VDDQ_GHJ_PWR_VR
J 0
(4000 50);
DISPLAY 1.021277 (4000 50);
PAINT ORANGE (4000 50);
DISPLAY INVISIBLE (4000 50);
FORCEADD PVDDQ_GHJ..1
(2700 225);
FORCEPROP 3 LASTPIN (2700 175) SIG_NAME PVDDQ_GHJ\g
J 0
(2710 185);
DISPLAY 0.659574 (2710 185);
PAINT MONO (2710 185);
DISPLAY INVISIBLE (2710 185);
FORCEPROP 1 LAST BODY_TYPE PLUMBING
J 0
(2655 182);
DISPLAY 0.340426 (2655 182);
PAINT GREEN (2655 182);
DISPLAY INVISIBLE (2655 182);
FORCEPROP 1 LAST VOLTAGE 1.2V
J 0
(2655 182);
DISPLAY 0.340426 (2655 182);
PAINT SKYBLUE (2655 182);
DISPLAY INVISIBLE (2655 182);
FORCEPROP 2 LAST CDS_LIB mstr_symbols
J 0
(2700 225);
PAINT ORANGE (2700 225);
DISPLAY INVISIBLE (2700 225);
FORCEPROP 1 LAST PATH I80
J 0
(2750 250);
DISPLAY 0.872340 (2750 250);
PAINT AQUA (2750 250);
DISPLAY INVISIBLE (2750 250);
FORCEPROP 2 LAST BOM_COST MEM_VRD_PVPP_AB
J 0
(2750 325);
PAINT MONO (2750 325);
DISPLAY INVISIBLE (2750 325);
FORCEPROP 1 LAST HDL_POWER PVDDQ_GHJ
J 1
(2700 275);
DISPLAY 0.872340 (2700 275);
PAINT GREEN (2700 275);
DISPLAY INVISIBLE (2700 275);
FORCEPROP 2 LAST ROOM VDDQ_GHJ_PWR_VR
J 0
(2925 325);
PAINT ORANGE (2925 325);
DISPLAY INVISIBLE (2925 325);
FORCEADD GND..1
(2700 -500);
FORCEPROP 3 LASTPIN (2700 -450) SIG_NAME GND\g
J 0
(2710 -440);
DISPLAY 0.659574 (2710 -440);
PAINT MONO (2710 -440);
DISPLAY INVISIBLE (2710 -440);
FORCEPROP 2 LAST BOM_COST MEM_VRD_PVPP_AB
J 0
(2375 -425);
PAINT MONO (2375 -425);
DISPLAY INVISIBLE (2375 -425);
FORCEPROP 1 LAST SIZE 1B
J 0
(2775 -550);
DISPLAY 0.893617 (2775 -550);
PAINT GREEN (2775 -550);
DISPLAY INVISIBLE (2775 -550);
FORCEPROP 1 LAST BODY_TYPE PLUMBING
J 0
(2655 -543);
DISPLAY 0.340426 (2655 -543);
PAINT GREEN (2655 -543);
DISPLAY INVISIBLE (2655 -543);
FORCEPROP 1 LAST HDL_POWER GND
J 0
(2700 -350);
DISPLAY 0.893617 (2700 -350);
PAINT GREEN (2700 -350);
DISPLAY INVISIBLE (2700 -350);
FORCEPROP 1 LAST PATH I81
J 0
(2775 -500);
DISPLAY 1.170213 (2775 -500);
PAINT AQUA (2775 -500);
DISPLAY INVISIBLE (2775 -500);
FORCEPROP 2 LAST CDS_LIB mstr_symbols
J 0
(2700 -500);
PAINT ORANGE (2700 -500);
DISPLAY INVISIBLE (2700 -500);
FORCEPROP 1 LAST VOLTAGE 0
J 0
(2700 -500);
PAINT SKYBLUE (2700 -500);
DISPLAY INVISIBLE (2700 -500);
FORCEADD CAP..1
(5000 2825);
FORCEPROP 1 LASTPIN (5000 2725) $PN 2
J 0
(5010 2705);
DISPLAY 0.617021 (5010 2705);
PAINT ORANGE (5010 2705);
FORCEPROP 1 LASTPIN (5000 2925) $PN 1
J 0
(5010 2905);
DISPLAY 0.617021 (5010 2905);
PAINT ORANGE (5010 2905);
FORCEPROP 1 LAST VOLTAGE 4V
J 0
(5050 2825);
DISPLAY 0.617021 (5050 2825);
PAINT SKYBLUE (5050 2825);
FORCEPROP 1 LAST LOCATION C8U1
J 0
(5050 2925);
DISPLAY 0.617021 (5050 2925);
PAINT AQUA (5050 2925);
FORCEPROP 1 LAST PART_NUMBER 602433-112
J 0
(5050 2675);
DISPLAY 0.617021 (5050 2675);
PAINT BLUE (5050 2675);
FORCEPROP 1 LAST VALUE 100UF
J 0
(5050 2875);
DISPLAY 0.617021 (5050 2875);
PAINT SKYBLUE (5050 2875);
FORCEPROP 1 LAST TOLERANCE 20%
J 0
(5050 2775);
DISPLAY 0.617021 (5050 2775);
PAINT SKYBLUE (5050 2775);
FORCEPROP 1 LAST PACK_TYPE 0805
J 0
(5050 2625);
DISPLAY 0.617021 (5050 2625);
PAINT SKYBLUE (5050 2625);
FORCEPROP 1 LAST MATERIAL X5R
J 0
(5050 2725);
DISPLAY 0.617021 (5050 2725);
PAINT SKYBLUE (5050 2725);
FORCEPROP 2 LAST CDS_LIB mstr_discrete
J 0
(5000 2825);
PAINT MONO (5000 2825);
DISPLAY INVISIBLE (5000 2825);
FORCEPROP 2 LAST CDS_LOCATION C8U1
J 0
(5050 2925);
DISPLAY 0.617021 (5050 2925);
PAINT AQUA (5050 2925);
DISPLAY INVISIBLE (5050 2925);
FORCEPROP 2 LAST SEC 1
J 0
(5050 3025);
DISPLAY 0.680851 (5050 3025);
PAINT MONO (5050 3025);
DISPLAY INVISIBLE (5050 3025);
FORCEPROP 2 LAST BOM_COST MEM_VRD_PVDDQ_CD
J 0
(5050 2975);
PAINT MONO (5050 2975);
DISPLAY INVISIBLE (5050 2975);
FORCEPROP 2 LAST SEC_TYPE 0805
J 0
(5050 3025);
DISPLAY 1.021277 (5050 3025);
PAINT ORANGE (5050 3025);
DISPLAY INVISIBLE (5050 3025);
FORCEPROP 1 LAST PATH I82
J 0
(5050 2975);
DISPLAY 0.978723 (5050 2975);
PAINT WHITE (5050 2975);
DISPLAY INVISIBLE (5050 2975);
FORCEPROP 2 LAST ROOM VDDQ_GHJ_PWR_VR
J 0
(5050 2975);
PAINT MONO (5050 2975);
DISPLAY INVISIBLE (5050 2975);
FORCEADD CAP..1
(4600 2825);
FORCEPROP 1 LAST LOCATION C8U8
J 0
(4650 2925);
DISPLAY 0.617021 (4650 2925);
PAINT AQUA (4650 2925);
FORCEPROP 1 LAST VALUE 100UF
J 0
(4650 2875);
DISPLAY 0.617021 (4650 2875);
PAINT SKYBLUE (4650 2875);
FORCEPROP 1 LAST TOLERANCE 20%
J 0
(4650 2775);
DISPLAY 0.617021 (4650 2775);
PAINT SKYBLUE (4650 2775);
FORCEPROP 1 LAST PACK_TYPE 0805
J 0
(4650 2625);
DISPLAY 0.617021 (4650 2625);
PAINT SKYBLUE (4650 2625);
FORCEPROP 1 LAST VOLTAGE 4V
J 0
(4650 2825);
DISPLAY 0.617021 (4650 2825);
PAINT SKYBLUE (4650 2825);
FORCEPROP 1 LAST MATERIAL X5R
J 0
(4650 2725);
DISPLAY 0.617021 (4650 2725);
PAINT SKYBLUE (4650 2725);
FORCEPROP 1 LASTPIN (4600 2725) $PN 2
J 0
(4610 2705);
DISPLAY 0.617021 (4610 2705);
PAINT ORANGE (4610 2705);
FORCEPROP 1 LASTPIN (4600 2925) $PN 1
J 0
(4610 2905);
DISPLAY 0.617021 (4610 2905);
PAINT ORANGE (4610 2905);
FORCEPROP 1 LAST PART_NUMBER 602433-112
J 0
(4650 2675);
DISPLAY 0.617021 (4650 2675);
PAINT BLUE (4650 2675);
FORCEPROP 2 LAST CDS_LIB mstr_discrete
J 0
(4600 2825);
PAINT MONO (4600 2825);
DISPLAY INVISIBLE (4600 2825);
FORCEPROP 2 LAST SEC_TYPE 0805
J 0
(4650 3025);
DISPLAY 1.021277 (4650 3025);
PAINT ORANGE (4650 3025);
DISPLAY INVISIBLE (4650 3025);
FORCEPROP 2 LAST BOM_COST MEM_VRD_PVDDQ_CD
J 0
(4650 2975);
PAINT MONO (4650 2975);
DISPLAY INVISIBLE (4650 2975);
FORCEPROP 2 LAST SEC 1
J 0
(4650 3025);
DISPLAY 0.680851 (4650 3025);
PAINT MONO (4650 3025);
DISPLAY INVISIBLE (4650 3025);
FORCEPROP 2 LAST CDS_LOCATION C8U8
J 0
(4650 2925);
DISPLAY 0.617021 (4650 2925);
PAINT AQUA (4650 2925);
DISPLAY INVISIBLE (4650 2925);
FORCEPROP 1 LAST PATH I83
J 0
(4650 2975);
DISPLAY 0.978723 (4650 2975);
PAINT WHITE (4650 2975);
DISPLAY INVISIBLE (4650 2975);
FORCEPROP 2 LAST ROOM VDDQ_GHJ_PWR_VR
J 0
(4650 2975);
PAINT MONO (4650 2975);
DISPLAY INVISIBLE (4650 2975);
FORCEADD CAP..1
(4250 2825);
FORCEPROP 1 LASTPIN (4250 2725) $PN 2
J 0
(4260 2705);
DISPLAY 0.617021 (4260 2705);
PAINT ORANGE (4260 2705);
FORCEPROP 1 LASTPIN (4250 2925) $PN 1
J 0
(4260 2905);
DISPLAY 0.617021 (4260 2905);
PAINT ORANGE (4260 2905);
FORCEPROP 1 LAST LOCATION C8U12
J 0
(4300 2925);
DISPLAY 0.617021 (4300 2925);
PAINT AQUA (4300 2925);
FORCEPROP 1 LAST PART_NUMBER 602433-112
J 0
(4300 2675);
DISPLAY 0.617021 (4300 2675);
PAINT BLUE (4300 2675);
FORCEPROP 1 LAST VALUE 100UF
J 0
(4300 2875);
DISPLAY 0.617021 (4300 2875);
PAINT SKYBLUE (4300 2875);
FORCEPROP 1 LAST TOLERANCE 20%
J 0
(4300 2775);
DISPLAY 0.617021 (4300 2775);
PAINT SKYBLUE (4300 2775);
FORCEPROP 1 LAST PACK_TYPE 0805
J 0
(4300 2625);
DISPLAY 0.617021 (4300 2625);
PAINT SKYBLUE (4300 2625);
FORCEPROP 1 LAST VOLTAGE 4V
J 0
(4300 2825);
DISPLAY 0.617021 (4300 2825);
PAINT SKYBLUE (4300 2825);
FORCEPROP 1 LAST MATERIAL X5R
J 0
(4300 2725);
DISPLAY 0.617021 (4300 2725);
PAINT SKYBLUE (4300 2725);
FORCEPROP 2 LAST CDS_LIB mstr_discrete
J 0
(4250 2825);
PAINT MONO (4250 2825);
DISPLAY INVISIBLE (4250 2825);
FORCEPROP 2 LAST CDS_LOCATION C8U12
J 0
(4300 2925);
DISPLAY 0.617021 (4300 2925);
PAINT AQUA (4300 2925);
DISPLAY INVISIBLE (4300 2925);
FORCEPROP 2 LAST SEC 1
J 0
(4300 3025);
DISPLAY 0.680851 (4300 3025);
PAINT MONO (4300 3025);
DISPLAY INVISIBLE (4300 3025);
FORCEPROP 2 LAST BOM_COST MEM_VRD_PVDDQ_CD
J 0
(4300 2975);
PAINT MONO (4300 2975);
DISPLAY INVISIBLE (4300 2975);
FORCEPROP 2 LAST SEC_TYPE 0805
J 0
(4300 3025);
DISPLAY 1.021277 (4300 3025);
PAINT ORANGE (4300 3025);
DISPLAY INVISIBLE (4300 3025);
FORCEPROP 1 LAST PATH I88
J 0
(4300 2975);
DISPLAY 0.978723 (4300 2975);
PAINT WHITE (4300 2975);
DISPLAY INVISIBLE (4300 2975);
FORCEPROP 2 LAST ROOM VDDQ_GHJ_PWR_VR
J 0
(4300 2975);
PAINT MONO (4300 2975);
DISPLAY INVISIBLE (4300 2975);
FORCEADD CAP..1
(3850 2825);
FORCEPROP 1 LAST MATERIAL X5R
J 0
(3900 2725);
DISPLAY 0.617021 (3900 2725);
PAINT SKYBLUE (3900 2725);
FORCEPROP 1 LAST PACK_TYPE 0805
J 0
(3900 2625);
DISPLAY 0.617021 (3900 2625);
PAINT SKYBLUE (3900 2625);
FORCEPROP 1 LAST TOLERANCE 20%
J 0
(3900 2775);
DISPLAY 0.617021 (3900 2775);
PAINT SKYBLUE (3900 2775);
FORCEPROP 1 LASTPIN (3850 2725) $PN 2
J 0
(3860 2705);
DISPLAY 0.617021 (3860 2705);
PAINT ORANGE (3860 2705);
FORCEPROP 1 LAST VOLTAGE 4V
J 0
(3900 2825);
DISPLAY 0.617021 (3900 2825);
PAINT SKYBLUE (3900 2825);
FORCEPROP 1 LASTPIN (3850 2925) $PN 1
J 0
(3860 2905);
DISPLAY 0.617021 (3860 2905);
PAINT ORANGE (3860 2905);
FORCEPROP 1 LAST LOCATION C8U11
J 0
(3900 2925);
DISPLAY 0.617021 (3900 2925);
PAINT AQUA (3900 2925);
FORCEPROP 1 LAST VALUE 100UF
J 0
(3900 2875);
DISPLAY 0.617021 (3900 2875);
PAINT SKYBLUE (3900 2875);
FORCEPROP 1 LAST PART_NUMBER 602433-112
J 0
(3900 2675);
DISPLAY 0.617021 (3900 2675);
PAINT BLUE (3900 2675);
FORCEPROP 2 LAST CDS_LIB mstr_discrete
J 0
(3850 2825);
PAINT MONO (3850 2825);
DISPLAY INVISIBLE (3850 2825);
FORCEPROP 2 LAST CDS_LOCATION C8U11
J 0
(3900 2925);
DISPLAY 0.617021 (3900 2925);
PAINT AQUA (3900 2925);
DISPLAY INVISIBLE (3900 2925);
FORCEPROP 2 LAST BOM_COST MEM_VRD_PVDDQ_CD
J 0
(3900 2975);
PAINT MONO (3900 2975);
DISPLAY INVISIBLE (3900 2975);
FORCEPROP 2 LAST SEC_TYPE 0805
J 0
(3900 3025);
DISPLAY 1.021277 (3900 3025);
PAINT ORANGE (3900 3025);
DISPLAY INVISIBLE (3900 3025);
FORCEPROP 2 LAST SEC 1
J 0
(3900 3025);
DISPLAY 0.680851 (3900 3025);
PAINT MONO (3900 3025);
DISPLAY INVISIBLE (3900 3025);
FORCEPROP 1 LAST PATH I89
J 0
(3900 2975);
DISPLAY 0.978723 (3900 2975);
PAINT WHITE (3900 2975);
DISPLAY INVISIBLE (3900 2975);
FORCEPROP 2 LAST ROOM VDDQ_GHJ_PWR_VR
J 0
(3900 2975);
PAINT MONO (3900 2975);
DISPLAY INVISIBLE (3900 2975);
FORCEADD CAP..1
(3500 2825);
FORCEPROP 1 LASTPIN (3500 2725) $PN 2
J 0
(3510 2705);
DISPLAY 0.617021 (3510 2705);
PAINT ORANGE (3510 2705);
FORCEPROP 1 LASTPIN (3500 2925) $PN 1
J 0
(3510 2905);
DISPLAY 0.617021 (3510 2905);
PAINT ORANGE (3510 2905);
FORCEPROP 1 LAST LOCATION C7T1
J 0
(3550 2925);
DISPLAY 0.617021 (3550 2925);
PAINT AQUA (3550 2925);
FORCEPROP 1 LAST PART_NUMBER 602433-112
J 0
(3550 2675);
DISPLAY 0.617021 (3550 2675);
PAINT BLUE (3550 2675);
FORCEPROP 1 LAST VALUE 100UF
J 0
(3550 2875);
DISPLAY 0.617021 (3550 2875);
PAINT SKYBLUE (3550 2875);
FORCEPROP 1 LAST TOLERANCE 20%
J 0
(3550 2775);
DISPLAY 0.617021 (3550 2775);
PAINT SKYBLUE (3550 2775);
FORCEPROP 1 LAST PACK_TYPE 0805
J 0
(3550 2625);
DISPLAY 0.617021 (3550 2625);
PAINT SKYBLUE (3550 2625);
FORCEPROP 1 LAST VOLTAGE 4V
J 0
(3550 2825);
DISPLAY 0.617021 (3550 2825);
PAINT SKYBLUE (3550 2825);
FORCEPROP 1 LAST MATERIAL X5R
J 0
(3550 2725);
DISPLAY 0.617021 (3550 2725);
PAINT SKYBLUE (3550 2725);
FORCEPROP 2 LAST CDS_LIB mstr_discrete
J 0
(3500 2825);
PAINT MONO (3500 2825);
DISPLAY INVISIBLE (3500 2825);
FORCEPROP 2 LAST CDS_LOCATION C7T1
J 0
(3550 2925);
DISPLAY 0.617021 (3550 2925);
PAINT AQUA (3550 2925);
DISPLAY INVISIBLE (3550 2925);
FORCEPROP 1 LAST PATH I90
J 0
(3550 2975);
DISPLAY 0.978723 (3550 2975);
PAINT WHITE (3550 2975);
DISPLAY INVISIBLE (3550 2975);
FORCEPROP 2 LAST SEC 1
J 0
(3550 3025);
DISPLAY 0.680851 (3550 3025);
PAINT MONO (3550 3025);
DISPLAY INVISIBLE (3550 3025);
FORCEPROP 2 LAST SEC_TYPE 0805
J 0
(3550 3025);
DISPLAY 1.021277 (3550 3025);
PAINT ORANGE (3550 3025);
DISPLAY INVISIBLE (3550 3025);
FORCEPROP 2 LAST BOM_COST MEM_VRD_PVDDQ_CD
J 0
(3550 2975);
PAINT MONO (3550 2975);
DISPLAY INVISIBLE (3550 2975);
FORCEPROP 2 LAST ROOM VDDQ_GHJ_PWR_VR
J 0
(3550 2975);
PAINT MONO (3550 2975);
DISPLAY INVISIBLE (3550 2975);
FORCEADD CAP..1
(3150 2825);
FORCEPROP 1 LASTPIN (3150 2725) $PN 2
J 0
(3160 2705);
DISPLAY 0.617021 (3160 2705);
PAINT ORANGE (3160 2705);
FORCEPROP 1 LAST MATERIAL X5R
J 0
(3200 2725);
DISPLAY 0.617021 (3200 2725);
PAINT SKYBLUE (3200 2725);
FORCEPROP 1 LAST PACK_TYPE 0805
J 0
(3200 2625);
DISPLAY 0.617021 (3200 2625);
PAINT SKYBLUE (3200 2625);
FORCEPROP 1 LAST TOLERANCE 20%
J 0
(3200 2775);
DISPLAY 0.617021 (3200 2775);
PAINT SKYBLUE (3200 2775);
FORCEPROP 1 LASTPIN (3150 2925) $PN 1
J 0
(3160 2905);
DISPLAY 0.617021 (3160 2905);
PAINT ORANGE (3160 2905);
FORCEPROP 1 LAST LOCATION C7U7
J 0
(3200 2925);
DISPLAY 0.617021 (3200 2925);
PAINT AQUA (3200 2925);
FORCEPROP 1 LAST VOLTAGE 4V
J 0
(3200 2825);
DISPLAY 0.617021 (3200 2825);
PAINT SKYBLUE (3200 2825);
FORCEPROP 1 LAST PART_NUMBER 602433-112
J 0
(3200 2675);
DISPLAY 0.617021 (3200 2675);
PAINT BLUE (3200 2675);
FORCEPROP 1 LAST VALUE 100UF
J 0
(3200 2875);
DISPLAY 0.617021 (3200 2875);
PAINT SKYBLUE (3200 2875);
FORCEPROP 2 LAST CDS_LIB mstr_discrete
J 0
(3150 2825);
PAINT MONO (3150 2825);
DISPLAY INVISIBLE (3150 2825);
FORCEPROP 2 LAST ROOM VDDQ_GHJ_PWR_VR
J 0
(3200 2975);
PAINT MONO (3200 2975);
DISPLAY INVISIBLE (3200 2975);
FORCEPROP 1 LAST PATH I91
J 0
(3200 2975);
DISPLAY 0.978723 (3200 2975);
PAINT WHITE (3200 2975);
DISPLAY INVISIBLE (3200 2975);
FORCEPROP 2 LAST CDS_LOCATION C7U7
J 0
(3200 2925);
DISPLAY 0.617021 (3200 2925);
PAINT AQUA (3200 2925);
DISPLAY INVISIBLE (3200 2925);
FORCEPROP 2 LAST SEC 1
J 0
(3200 3025);
DISPLAY 0.680851 (3200 3025);
PAINT MONO (3200 3025);
DISPLAY INVISIBLE (3200 3025);
FORCEPROP 2 LAST SEC_TYPE 0805
J 0
(3200 3025);
DISPLAY 1.021277 (3200 3025);
PAINT ORANGE (3200 3025);
DISPLAY INVISIBLE (3200 3025);
FORCEPROP 2 LAST BOM_COST MEM_VRD_PVDDQ_CD
J 0
(3200 2975);
PAINT MONO (3200 2975);
DISPLAY INVISIBLE (3200 2975);
FORCEADD CAP..1
(2750 2825);
FORCEPROP 1 LASTPIN (2750 2725) $PN 2
J 0
(2760 2705);
DISPLAY 0.617021 (2760 2705);
PAINT ORANGE (2760 2705);
FORCEPROP 1 LASTPIN (2750 2925) $PN 1
J 0
(2760 2905);
DISPLAY 0.617021 (2760 2905);
PAINT ORANGE (2760 2905);
FORCEPROP 1 LAST LOCATION C2G7
J 0
(2800 2925);
DISPLAY 0.617021 (2800 2925);
PAINT AQUA (2800 2925);
FORCEPROP 1 LAST VALUE 100UF
J 0
(2800 2875);
DISPLAY 0.617021 (2800 2875);
PAINT SKYBLUE (2800 2875);
FORCEPROP 1 LAST TOLERANCE 20%
J 0
(2800 2775);
DISPLAY 0.617021 (2800 2775);
PAINT SKYBLUE (2800 2775);
FORCEPROP 1 LAST PACK_TYPE 0805
J 0
(2800 2625);
DISPLAY 0.617021 (2800 2625);
PAINT SKYBLUE (2800 2625);
FORCEPROP 1 LAST VOLTAGE 4V
J 0
(2800 2825);
DISPLAY 0.617021 (2800 2825);
PAINT SKYBLUE (2800 2825);
FORCEPROP 1 LAST MATERIAL X5R
J 0
(2800 2725);
DISPLAY 0.617021 (2800 2725);
PAINT SKYBLUE (2800 2725);
FORCEPROP 1 LAST PART_NUMBER 602433-112
J 0
(2800 2675);
DISPLAY 0.617021 (2800 2675);
PAINT BLUE (2800 2675);
FORCEPROP 2 LAST CDS_LIB mstr_discrete
J 0
(2750 2825);
PAINT MONO (2750 2825);
DISPLAY INVISIBLE (2750 2825);
FORCEPROP 2 LAST CDS_LOCATION C2G7
J 0
(2800 2925);
DISPLAY 0.617021 (2800 2925);
PAINT AQUA (2800 2925);
DISPLAY INVISIBLE (2800 2925);
FORCEPROP 1 LAST PATH I92
J 0
(2800 2975);
DISPLAY 0.978723 (2800 2975);
PAINT WHITE (2800 2975);
DISPLAY INVISIBLE (2800 2975);
FORCEPROP 2 LAST SEC 1
J 0
(2800 3025);
DISPLAY 0.680851 (2800 3025);
PAINT MONO (2800 3025);
DISPLAY INVISIBLE (2800 3025);
FORCEPROP 2 LAST SEC_TYPE 0805
J 0
(2800 3025);
DISPLAY 1.021277 (2800 3025);
PAINT ORANGE (2800 3025);
DISPLAY INVISIBLE (2800 3025);
FORCEPROP 2 LAST BOM_COST MEM_VRD_PVDDQ_CD
J 0
(2800 2975);
PAINT MONO (2800 2975);
DISPLAY INVISIBLE (2800 2975);
FORCEPROP 2 LAST ROOM VDDQ_GHJ_PWR_VR
J 0
(2800 2975);
PAINT MONO (2800 2975);
DISPLAY INVISIBLE (2800 2975);
FORCEADD PVDDQ_GHJ..1
(2400 3100);
FORCEPROP 3 LASTPIN (2400 3050) SIG_NAME PVDDQ_GHJ\g
J 0
(2410 3060);
DISPLAY 0.659574 (2410 3060);
PAINT MONO (2410 3060);
DISPLAY INVISIBLE (2410 3060);
FORCEPROP 1 LAST BODY_TYPE PLUMBING
J 0
(2355 3057);
DISPLAY 0.340426 (2355 3057);
PAINT GREEN (2355 3057);
DISPLAY INVISIBLE (2355 3057);
FORCEPROP 1 LAST VOLTAGE 1.2V
J 0
(2355 3057);
DISPLAY 0.340426 (2355 3057);
PAINT SKYBLUE (2355 3057);
DISPLAY INVISIBLE (2355 3057);
FORCEPROP 2 LAST BOM_COST MEM_VRD_PVDDQ_CD
J 0
(2475 3200);
PAINT MONO (2475 3200);
DISPLAY INVISIBLE (2475 3200);
FORCEPROP 2 LAST CDS_LIB mstr_symbols
J 0
(2400 3100);
PAINT ORANGE (2400 3100);
DISPLAY INVISIBLE (2400 3100);
FORCEPROP 1 LAST PATH I93
J 0
(2450 3125);
DISPLAY 0.872340 (2450 3125);
PAINT AQUA (2450 3125);
DISPLAY INVISIBLE (2450 3125);
FORCEPROP 2 LAST ROOM VDDQ_GHJ_PWR_VR
J 0
(2650 3200);
PAINT ORANGE (2650 3200);
DISPLAY INVISIBLE (2650 3200);
FORCEPROP 1 LAST HDL_POWER PVDDQ_GHJ
J 1
(2400 3150);
DISPLAY 0.872340 (2400 3150);
PAINT GREEN (2400 3150);
DISPLAY INVISIBLE (2400 3150);
FORCEADD GND..1
(4125 2450);
FORCEPROP 3 LASTPIN (4125 2500) SIG_NAME GND\g
J 0
(4135 2510);
DISPLAY 0.659574 (4135 2510);
PAINT MONO (4135 2510);
DISPLAY INVISIBLE (4135 2510);
FORCEPROP 2 LAST ROOM VDDQ_GHJ_PWR_VR
J 0
(3575 2525);
PAINT ORANGE (3575 2525);
DISPLAY INVISIBLE (3575 2525);
FORCEPROP 1 LAST BODY_TYPE PLUMBING
J 0
(4080 2407);
DISPLAY 0.340426 (4080 2407);
PAINT GREEN (4080 2407);
DISPLAY INVISIBLE (4080 2407);
FORCEPROP 2 LAST BOM_COST MEM_VRD_PVDDQ_CD
J 0
(3800 2525);
PAINT MONO (3800 2525);
DISPLAY INVISIBLE (3800 2525);
FORCEPROP 1 LAST VOLTAGE 0
J 0
(4125 2450);
PAINT SKYBLUE (4125 2450);
DISPLAY INVISIBLE (4125 2450);
FORCEPROP 2 LAST CDS_LIB mstr_symbols
J 0
(4125 2450);
PAINT ORANGE (4125 2450);
DISPLAY INVISIBLE (4125 2450);
FORCEPROP 1 LAST SIZE 1B
J 0
(4200 2400);
DISPLAY 0.893617 (4200 2400);
PAINT GREEN (4200 2400);
DISPLAY INVISIBLE (4200 2400);
FORCEPROP 1 LAST PATH I94
J 0
(4200 2450);
DISPLAY 1.170213 (4200 2450);
PAINT AQUA (4200 2450);
DISPLAY INVISIBLE (4200 2450);
FORCEPROP 1 LAST HDL_POWER GND
J 0
(4125 2600);
DISPLAY 0.893617 (4125 2600);
PAINT GREEN (4125 2600);
DISPLAY INVISIBLE (4125 2600);
FORCEADD DNS..3
(-270 1870);
PAINT RED (-270 1870);
FORCEPROP 1 LAST COMMENT_BODY TRUE
R 1
J 0
(-195 1645);
DISPLAY 0.872340 (-195 1645);
PAINT GREEN (-195 1645);
DISPLAY INVISIBLE (-195 1645);
FORCEPROP 2 LAST CDS_LIB mstr_misc
J 0
(-270 1870);
PAINT ORANGE (-270 1870);
DISPLAY INVISIBLE (-270 1870);
FORCEADD DNS..2
(-645 2070);
PAINT RED (-645 2070);
FORCEPROP 1 LAST COMMENT_BODY TRUE
R 1
J 0
(-570 1845);
DISPLAY 0.872340 (-570 1845);
PAINT GREEN (-570 1845);
DISPLAY INVISIBLE (-570 1845);
FORCEPROP 2 LAST CDS_LIB mstr_misc
J 0
(-645 2070);
PAINT ORANGE (-645 2070);
DISPLAY INVISIBLE (-645 2070);
FORCEADD DNS..3
(-245 2320);
PAINT RED (-245 2320);
FORCEPROP 1 LAST COMMENT_BODY TRUE
R 1
J 0
(-170 2095);
DISPLAY 0.872340 (-170 2095);
PAINT GREEN (-170 2095);
DISPLAY INVISIBLE (-170 2095);
FORCEPROP 2 LAST CDS_LIB mstr_misc
J 0
(-245 2320);
PAINT ORANGE (-245 2320);
DISPLAY INVISIBLE (-245 2320);
FORCEADD INTEL_CORP_BPAGE..1
(5475 -1450);
FORCEPROP 1 LAST CDS_CON_LAST_MODIFIED Tue Dec 01 11:52:27 2015
J 0
(4050 -1125);
PAINT GREEN (4050 -1125);
DISPLAY INVISIBLE (4050 -1125);
FORCEPROP 1 LAST CUSTOM_TXT_CDS <CURRENT_DESIGN_SHEET> OF <TOTAL_DESIGN_SHEETS>
J 0
(4975 -1425);
PAINT GREEN (4975 -1425);
FORCEPROP 2 LAST CUSTOM_TXT_CDS <XR_PAGE_TITLE>
J 0
(-2415 3800);
DISPLAY 0.638298 (-2415 3800);
PAINT PINK (-2415 3800);
DISPLAY INVISIBLE (-2415 3800);
FORCEPROP 2 LAST CUSTOM_TXT_CDS <CON_LAST_MODIFIED>
J 0
(4525 -1100);
PAINT GREEN (4525 -1100);
FORCEPROP 2 LAST CUSTOM_TXT_CDS <CON_PAGE_NUM> OF <CON_TOTAL_PAGES>
J 0
(4975 -1425);
PAINT GREEN (4975 -1425);
FORCEPROP 1 LAST SCH_TITLE VDDQ GHJ DECAP (3 OF 3)
J 0
(-2475 -1400);
DISPLAY 1.212766 (-2475 -1400);
PAINT GREEN (-2475 -1400);
FORCEPROP 1 LAST SCH_ADDRESS2 P.O. BOX 58119
J 0
(1500 -1375);
DISPLAY 0.617021 (1500 -1375);
PAINT GREEN (1500 -1375);
FORCEPROP 1 LAST SCH_ADDRESS3 Santa Clara, CA 95052-8119
J 0
(1500 -1425);
DISPLAY 0.617021 (1500 -1425);
PAINT GREEN (1500 -1425);
FORCEPROP 1 LAST SCH_ADDRESS1 2200 Mission College Blvd.
J 0
(1500 -1325);
DISPLAY 0.617021 (1500 -1325);
PAINT GREEN (1500 -1325);
FORCEPROP 1 LAST SCH_NUMBER H4694802
J 0
(4175 -1300);
DISPLAY 1.212766 (4175 -1300);
PAINT YELLOW (4175 -1300);
FORCEPROP 1 LAST SCH_DEPT BESD
J 1
(1025 -1350);
DISPLAY 1.212766 (1025 -1350);
PAINT YELLOW (1025 -1350);
FORCEPROP 1 LAST SCH_REV 2.420
J 0
(5225 -1300);
DISPLAY 0.978723 (5225 -1300);
PAINT YELLOW (5225 -1300);
FORCEPROP 2 LAST ROOM VDDQ_GHJ_PWR_VR
J 0
(-2625 3650);
PAINT ORANGE (-2625 3650);
DISPLAY INVISIBLE (-2625 3650);
FORCEPROP 2 LAST PAGE_BORDER TRUE
J 0
(-2415 3800);
DISPLAY 0.851064 (-2415 3800);
PAINT PINK (-2415 3800);
DISPLAY INVISIBLE (-2415 3800);
FORCEPROP 2 LAST CDS_LIB mstr_symbols
J 0
(5475 -1450);
PAINT ORANGE (5475 -1450);
DISPLAY INVISIBLE (5475 -1450);
FORCEPROP 1 LAST COMMENT_BODY TRUE
J 0
(5487 -1438);
DISPLAY 0.446809 (5487 -1438);
PAINT GREEN (5487 -1438);
DISPLAY INVISIBLE (5487 -1438);
FORCEPROP 2 LAST CDS_XR_PAGE_TITLE CR-225 : @BASEBOARD_FAB2_LIB.BASEBOARD_FAB2(SCH_1):PAGE225
J 0
(-2415 3800);
DISPLAY 0.638298 (-2415 3800);
PAINT PINK (-2415 3800);
DISPLAY INVISIBLE (-2415 3800);
WIRE 16 -1 (4400 1825)(4400 1900);
WIRE 16 -1 (4400 1900)(4000 1900);
WIRE 16 -1 (4000 1825)(4000 1900);
WIRE 16 -1 (4000 1900)(3650 1900);
WIRE 16 -1 (3650 1825)(3650 1900);
WIRE 16 -1 (3650 1900)(3300 1900);
WIRE 16 -1 (3300 1825)(3300 1900);
WIRE 16 -1 (3300 1900)(2900 1900);
WIRE 16 -1 (2900 1825)(2900 1900);
WIRE 16 -1 (2550 1900)(2900 1900);
WIRE 16 -1 (2550 1900)(2550 1825);
WIRE 16 -1 (2550 1900)(2550 1950);
WIRE 16 -1 (2550 1625)(2550 1475);
WIRE 16 -1 (2550 1475)(2900 1475);
WIRE 16 -1 (2900 1625)(2900 1475);
WIRE 16 -1 (2900 1475)(3300 1475);
WIRE 16 -1 (3300 1625)(3300 1475);
WIRE 16 -1 (3300 1475)(3650 1475);
WIRE 16 -1 (3650 1625)(3650 1475);
WIRE 16 -1 (3650 1475)(4000 1475);
WIRE 16 -1 (4000 1625)(4000 1475);
WIRE 16 -1 (4275 1475)(4000 1475);
WIRE 16 -1 (4275 1475)(4400 1475);
WIRE 16 -1 (4275 1400)(4275 1475);
WIRE 16 -1 (4400 1625)(4400 1475);
WIRE 16 -1 (50 1350)(50 1275);
WIRE 16 -1 (-375 1350)(50 1350);
WIRE 16 -1 (-375 1350)(-375 1275);
WIRE 16 -1 (-800 1350)(-375 1350);
WIRE 16 -1 (-800 1350)(-800 1275);
WIRE 16 -1 (-1250 1350)(-800 1350);
WIRE 16 -1 (-1250 1275)(-1250 1350);
WIRE 16 -1 (-1250 1350)(-1250 1375);
WIRE 16 -1 (-1575 1375)(-1250 1375);
WIRE 16 -1 (-1250 1375)(-1250 1525);
WIRE 16 -1 (50 950)(50 1075);
WIRE 16 -1 (-375 950)(50 950);
WIRE 16 -1 (-375 950)(-375 1075);
WIRE 16 -1 (-800 950)(-375 950);
WIRE 16 -1 (-800 950)(-800 1075);
WIRE 16 -1 (-1250 950)(-800 950);
WIRE 16 -1 (-1250 1075)(-1250 950);
WIRE 16 -1 (-1250 950)(-1250 875);
WIRE 16 -1 (-2000 1375)(-1775 1375);
WIRE 16 -1 (-2000 1375)(-2000 1525);
WIRE 16 -1 (-1550 2950)(-1550 2800);
WIRE 16 -1 (-1550 2800)(-1200 2800);
WIRE 16 -1 (-1200 2950)(-1200 2800);
WIRE 16 -1 (-1200 2800)(-850 2800);
WIRE 16 -1 (-850 2950)(-850 2800);
WIRE 16 -1 (-850 2800)(-450 2800);
WIRE 16 -1 (-450 2950)(-450 2800);
WIRE 16 -1 (-450 2725)(-450 2800);
WIRE 16 -1 (-1950 3150)(-1950 3225);
WIRE 16 -1 (-2300 3225)(-1950 3225);
WIRE 16 -1 (-2300 3225)(-2300 3275);
WIRE 16 -1 (-2300 3225)(-2300 3150);
WIRE 16 -1 (3350 1075)(3350 1150);
WIRE 16 -1 (3350 1150)(2950 1150);
WIRE 16 -1 (2950 1075)(2950 1150);
WIRE 16 -1 (2600 1150)(2950 1150);
WIRE 16 -1 (2600 1150)(2600 1200);
WIRE 16 -1 (2600 1150)(2600 1075);
WIRE 16 -1 (2600 875)(2600 725);
WIRE 16 -1 (2600 725)(2950 725);
WIRE 16 -1 (2950 875)(2950 725);
WIRE 16 -1 (2950 725)(3350 725);
WIRE 16 -1 (3350 875)(3350 725);
WIRE 16 -1 (3350 725)(3425 725);
WIRE 16 -1 (3425 625)(3425 725);
WIRE 16 -1 (-450 3150)(-450 3225);
WIRE 16 -1 (-450 3225)(-850 3225);
WIRE 16 -1 (-850 3150)(-850 3225);
WIRE 16 -1 (-850 3225)(-1200 3225);
WIRE 16 -1 (-1200 3150)(-1200 3225);
WIRE 16 -1 (-1200 3225)(-1550 3225);
WIRE 16 -1 (-1550 3150)(-1550 3225);
WIRE 16 -1 (-1550 3225)(-1550 3275);
WIRE 16 -1 (-2300 2950)(-2300 2800);
WIRE 16 -1 (-2300 2800)(-1950 2800);
WIRE 16 -1 (-1950 2950)(-1950 2800);
WIRE 16 -1 (-1950 2750)(-1950 2800);
WIRE 16 -1 (2100 350)(2100 400);
WIRE 16 -1 (2100 400)(1825 400);
WIRE 16 -1 (1825 350)(1825 400);
WIRE 16 -1 (1825 400)(1525 400);
WIRE 16 -1 (1525 350)(1525 400);
WIRE 16 -1 (1525 400)(1225 400);
WIRE 16 -1 (1225 350)(1225 400);
WIRE 16 -1 (1225 400)(950 400);
WIRE 16 -1 (950 350)(950 400);
WIRE 16 -1 (950 400)(675 400);
WIRE 16 -1 (675 350)(675 400);
WIRE 16 -1 (675 400)(375 400);
WIRE 16 -1 (375 350)(375 400);
WIRE 16 -1 (375 400)(75 400);
WIRE 16 -1 (75 350)(75 400);
WIRE 16 -1 (75 400)(-250 400);
WIRE 16 -1 (-250 350)(-250 400);
WIRE 16 -1 (-250 400)(-525 400);
WIRE 16 -1 (-525 350)(-525 400);
WIRE 16 -1 (-525 400)(-825 400);
WIRE 16 -1 (-825 350)(-825 400);
WIRE 16 -1 (-825 400)(-1125 400);
WIRE 16 -1 (-1125 350)(-1125 400);
WIRE 16 -1 (-1125 400)(-1400 400);
WIRE 16 -1 (-1400 350)(-1400 400);
WIRE 16 -1 (-1675 400)(-1400 400);
WIRE 16 -1 (-1675 350)(-1675 400);
WIRE 16 -1 (-1975 400)(-1675 400);
WIRE 16 -1 (-1975 350)(-1975 400);
WIRE 16 -1 (-2275 400)(-1975 400);
WIRE 16 -1 (-2275 350)(-2275 400);
WIRE 16 -1 (-2275 400)(-2275 450);
WIRE 16 -1 (2100 150)(2100 75);
WIRE 16 -1 (2100 75)(1825 75);
WIRE 16 -1 (1825 150)(1825 75);
WIRE 16 -1 (1825 75)(1525 75);
WIRE 16 -1 (1525 150)(1525 75);
WIRE 16 -1 (1525 75)(1225 75);
WIRE 16 -1 (1225 150)(1225 75);
WIRE 16 -1 (1225 75)(950 75);
WIRE 16 -1 (950 150)(950 75);
WIRE 16 -1 (950 75)(675 75);
WIRE 16 -1 (675 150)(675 75);
WIRE 16 -1 (675 75)(375 75);
WIRE 16 -1 (375 150)(375 75);
WIRE 16 -1 (375 75)(75 75);
WIRE 16 -1 (75 150)(75 75);
WIRE 16 -1 (75 75)(-250 75);
WIRE 16 -1 (-250 150)(-250 75);
WIRE 16 -1 (-250 75)(-525 75);
WIRE 16 -1 (-525 150)(-525 75);
WIRE 16 -1 (-525 75)(-825 75);
WIRE 16 -1 (-825 150)(-825 75);
WIRE 16 -1 (-825 75)(-1125 75);
WIRE 16 -1 (-1125 150)(-1125 75);
WIRE 16 -1 (-1125 75)(-1400 75);
WIRE 16 -1 (-1400 150)(-1400 75);
WIRE 16 -1 (-1675 75)(-1400 75);
WIRE 16 -1 (-1675 150)(-1675 75);
WIRE 16 -1 (-1675 75)(-1975 75);
WIRE 16 -1 (-1975 150)(-1975 75);
WIRE 16 -1 (-1975 75)(-2275 75);
WIRE 16 -1 (-2275 150)(-2275 75);
WIRE 16 -1 (-2275 75)(-2275 25);
WIRE 16 -1 (2125 -350)(2125 -300);
WIRE 16 -1 (2125 -300)(1850 -300);
WIRE 16 -1 (1850 -350)(1850 -300);
WIRE 16 -1 (1850 -300)(1550 -300);
WIRE 16 -1 (1550 -350)(1550 -300);
WIRE 16 -1 (1550 -300)(1250 -300);
WIRE 16 -1 (1250 -350)(1250 -300);
WIRE 16 -1 (1250 -300)(975 -300);
WIRE 16 -1 (975 -350)(975 -300);
WIRE 16 -1 (975 -300)(700 -300);
WIRE 16 -1 (700 -350)(700 -300);
WIRE 16 -1 (700 -300)(400 -300);
WIRE 16 -1 (400 -350)(400 -300);
WIRE 16 -1 (400 -300)(100 -300);
WIRE 16 -1 (100 -350)(100 -300);
WIRE 16 -1 (100 -300)(-225 -300);
WIRE 16 -1 (-225 -350)(-225 -300);
WIRE 16 -1 (-225 -300)(-500 -300);
WIRE 16 -1 (-500 -350)(-500 -300);
WIRE 16 -1 (-500 -300)(-800 -300);
WIRE 16 -1 (-800 -350)(-800 -300);
WIRE 16 -1 (-800 -300)(-1100 -300);
WIRE 16 -1 (-1100 -350)(-1100 -300);
WIRE 16 -1 (-1100 -300)(-1375 -300);
WIRE 16 -1 (-1375 -350)(-1375 -300);
WIRE 16 -1 (-1650 -300)(-1375 -300);
WIRE 16 -1 (-1650 -350)(-1650 -300);
WIRE 16 -1 (-1950 -300)(-1650 -300);
WIRE 16 -1 (-1950 -350)(-1950 -300);
WIRE 16 -1 (-2250 -300)(-1950 -300);
WIRE 16 -1 (-2250 -350)(-2250 -300);
WIRE 16 -1 (-2250 -300)(-2250 -250);
WIRE 16 -1 (2125 -550)(2125 -625);
WIRE 16 -1 (2125 -625)(1850 -625);
WIRE 16 -1 (1850 -550)(1850 -625);
WIRE 16 -1 (1850 -625)(1550 -625);
WIRE 16 -1 (1550 -550)(1550 -625);
WIRE 16 -1 (1550 -625)(1250 -625);
WIRE 16 -1 (1250 -550)(1250 -625);
WIRE 16 -1 (1250 -625)(975 -625);
WIRE 16 -1 (975 -550)(975 -625);
WIRE 16 -1 (975 -625)(700 -625);
WIRE 16 -1 (700 -550)(700 -625);
WIRE 16 -1 (700 -625)(400 -625);
WIRE 16 -1 (400 -550)(400 -625);
WIRE 16 -1 (400 -625)(100 -625);
WIRE 16 -1 (100 -550)(100 -625);
WIRE 16 -1 (100 -625)(-225 -625);
WIRE 16 -1 (-225 -550)(-225 -625);
WIRE 16 -1 (-225 -625)(-500 -625);
WIRE 16 -1 (-500 -550)(-500 -625);
WIRE 16 -1 (-500 -625)(-800 -625);
WIRE 16 -1 (-800 -550)(-800 -625);
WIRE 16 -1 (-800 -625)(-1100 -625);
WIRE 16 -1 (-1100 -550)(-1100 -625);
WIRE 16 -1 (-1100 -625)(-1375 -625);
WIRE 16 -1 (-1375 -550)(-1375 -625);
WIRE 16 -1 (-1650 -625)(-1375 -625);
WIRE 16 -1 (-1650 -550)(-1650 -625);
WIRE 16 -1 (-1650 -625)(-1950 -625);
WIRE 16 -1 (-1950 -550)(-1950 -625);
WIRE 16 -1 (-1950 -625)(-2250 -625);
WIRE 16 -1 (-2250 -550)(-2250 -625);
WIRE 16 -1 (-2250 -625)(-2250 -675);
WIRE 16 -1 (100 1800)(100 1875);
WIRE 16 -1 (100 1875)(-125 1875);
WIRE 16 -1 (100 2400)(100 2325);
WIRE 16 -1 (100 2325)(-100 2325);
WIRE 16 -1 (4325 25)(4325 100);
WIRE 16 -1 (3950 100)(4325 100);
WIRE 16 -1 (3950 0)(3950 100);
WIRE 16 -1 (3550 100)(3950 100);
WIRE 16 -1 (3550 25)(3550 100);
WIRE 16 -1 (3125 100)(3550 100);
WIRE 16 -1 (3125 25)(3125 100);
WIRE 16 -1 (2700 100)(3125 100);
WIRE 16 -1 (2700 25)(2700 100);
WIRE 16 -1 (2700 100)(2700 175);
WIRE 16 -1 (4325 -175)(4325 -325);
WIRE 16 -1 (3950 -325)(4325 -325);
WIRE 16 -1 (3950 -200)(3950 -325);
WIRE 16 -1 (3950 -325)(3550 -325);
WIRE 16 -1 (3550 -175)(3550 -325);
WIRE 16 -1 (3550 -325)(3125 -325);
WIRE 16 -1 (3125 -175)(3125 -325);
WIRE 16 -1 (3125 -325)(2700 -325);
WIRE 16 -1 (2700 -325)(2700 -175);
WIRE 16 -1 (2700 -325)(2700 -450);
WIRE 16 -1 (5000 2925)(5000 3000);
WIRE 16 -1 (5000 3000)(4600 3000);
WIRE 16 -1 (4600 2925)(4600 3000);
WIRE 16 -1 (4600 3000)(4250 3000);
WIRE 16 -1 (4250 2925)(4250 3000);
WIRE 16 -1 (4250 3000)(3850 3000);
WIRE 16 -1 (3850 2925)(3850 3000);
WIRE 16 -1 (3850 3000)(3500 3000);
WIRE 16 -1 (3500 2925)(3500 3000);
WIRE 16 -1 (3500 3000)(3150 3000);
WIRE 16 -1 (3150 2925)(3150 3000);
WIRE 16 -1 (3150 3000)(2750 3000);
WIRE 16 -1 (2750 2925)(2750 3000);
WIRE 16 -1 (2400 3000)(2750 3000);
WIRE 16 -1 (2400 3000)(2400 2925);
WIRE 16 -1 (2400 3000)(2400 3050);
WIRE 16 -1 (2400 2725)(2400 2575);
WIRE 16 -1 (2400 2575)(2750 2575);
WIRE 16 -1 (2750 2725)(2750 2575);
WIRE 16 -1 (2750 2575)(3150 2575);
WIRE 16 -1 (3150 2725)(3150 2575);
WIRE 16 -1 (3150 2575)(3500 2575);
WIRE 16 -1 (3500 2725)(3500 2575);
WIRE 16 -1 (3500 2575)(3850 2575);
WIRE 16 -1 (3850 2725)(3850 2575);
WIRE 16 -1 (4125 2575)(3850 2575);
WIRE 16 -1 (4125 2575)(4250 2575);
WIRE 16 -1 (4125 2500)(4125 2575);
WIRE 16 -1 (4250 2575)(4600 2575);
WIRE 16 -1 (4250 2725)(4250 2575);
WIRE 16 -1 (4600 2575)(5000 2575);
WIRE 16 -1 (4600 2725)(4600 2575);
WIRE 16 -1 (5000 2725)(5000 2575);
WIRE 16 682 (-125 3450)(-125 2550);
WIRE 16 682 (-125 3450)(-2475 3450);
WIRE 16 682 (-125 2550)(-2475 2550);
WIRE 16 682 (-2475 2550)(-2475 3450);
WIRE 16 -1 (-650 1975)(-650 1875);
WIRE 16 -1 (-425 1875)(-650 1875);
WIRE 16 -1 (-650 1875)(-750 1875);
WIRE 16 -1 (-750 2100)(-750 1875);
WIRE 16 -1 (-1150 2100)(-750 2100);
WIRE 16 -1 (-1150 2050)(-1150 2100);
WIRE 16 -1 (-1875 2050)(-1150 2050);
FORCEPROP 2 LAST SIG_NAME VSENSE_PVDDQ_GHJ_N
J 0
(-1885 2060);
DISPLAY 0.617021 (-1885 2060);
PAINT ORANGE (-1885 2060);
WIRE 16 2175 (5375 3375)(5375 2250);
WIRE 16 2175 (2175 3375)(5375 3375);
WIRE 16 2175 (5375 2250)(5375 500);
WIRE 16 2175 (2300 2250)(5375 2250);
WIRE 16 2175 (5375 500)(2175 500);
WIRE 16 2175 (2175 500)(2175 3375);
WIRE 16 682 (5050 350)(2525 350);
WIRE 16 682 (5050 -625)(5050 350);
WIRE 16 682 (2525 350)(2525 -625);
WIRE 16 682 (2525 -625)(5050 -625);
WIRE 16 -1 (-400 2325)(-650 2325);
WIRE 16 -1 (-650 2325)(-750 2325);
WIRE 16 -1 (-650 2175)(-650 2325);
WIRE 16 -1 (-750 2325)(-750 2175);
WIRE 16 -1 (-750 2175)(-1150 2175);
WIRE 16 -1 (-1150 2175)(-1150 2300);
WIRE 16 -1 (-1150 2300)(-1875 2300);
FORCEPROP 2 LAST SIG_NAME VSENSE_PVDDQ_GHJ_P
J 0
(-1880 2315);
DISPLAY 0.617021 (-1880 2315);
PAINT ORANGE (-1880 2315);
DOT 1 (-2250 -625);
DOT 1 (-2250 -300);
DOT 1 (-1950 -625);
DOT 1 (-1650 -625);
DOT 1 (-1950 -300);
DOT 1 (-1650 -300);
DOT 1 (-1375 -625);
DOT 1 (-1100 -625);
DOT 1 (-1375 -300);
DOT 1 (-1100 -300);
DOT 1 (-800 -625);
DOT 1 (-800 -300);
DOT 1 (-500 -300);
DOT 1 (-500 -625);
DOT 1 (-225 -625);
DOT 1 (-225 -300);
DOT 1 (-2275 75);
DOT 1 (-2275 400);
DOT 1 (-2300 3225);
DOT 1 (-1975 75);
DOT 1 (-1975 400);
DOT 1 (-1675 75);
DOT 1 (-1675 400);
DOT 1 (-1400 75);
DOT 1 (-1400 400);
DOT 1 (-1125 75);
DOT 1 (-1125 400);
DOT 1 (-1250 950);
DOT 1 (-1250 1375);
DOT 1 (-1250 1350);
DOT 1 (-825 75);
DOT 1 (-825 400);
DOT 1 (-525 75);
DOT 1 (-525 400);
DOT 1 (-800 950);
DOT 1 (-250 400);
DOT 1 (-250 75);
DOT 1 (-375 950);
DOT 1 (-800 1350);
DOT 1 (-650 1875);
DOT 1 (-375 1350);
DOT 1 (-1950 2800);
DOT 1 (-1200 2800);
DOT 1 (-1550 3225);
DOT 1 (-1200 3225);
DOT 1 (-650 2325);
DOT 1 (-850 2800);
DOT 1 (-450 2800);
DOT 1 (-850 3225);
DOT 1 (100 -625);
DOT 1 (400 -625);
DOT 1 (100 -300);
DOT 1 (400 -300);
DOT 1 (700 -625);
DOT 1 (975 -625);
DOT 1 (700 -300);
DOT 1 (975 -300);
DOT 1 (1250 -625);
DOT 1 (1250 -300);
DOT 1 (1550 -625);
DOT 1 (1850 -625);
DOT 1 (1550 -300);
DOT 1 (1850 -300);
DOT 1 (2700 -325);
DOT 1 (3125 -325);
DOT 1 (3550 -325);
DOT 1 (3950 -325);
DOT 1 (75 75);
DOT 1 (75 400);
DOT 1 (375 75);
DOT 1 (375 400);
DOT 1 (675 75);
DOT 1 (675 400);
DOT 1 (950 75);
DOT 1 (950 400);
DOT 1 (1225 75);
DOT 1 (1225 400);
DOT 1 (1525 75);
DOT 1 (1525 400);
DOT 1 (1825 75);
DOT 1 (1825 400);
DOT 1 (2700 100);
DOT 1 (2950 725);
DOT 1 (2550 1900);
DOT 1 (2600 1150);
DOT 1 (2950 1150);
DOT 1 (2900 1475);
DOT 1 (2900 1900);
DOT 1 (3125 100);
DOT 1 (3550 100);
DOT 1 (3350 725);
DOT 1 (3950 100);
DOT 1 (3300 1475);
DOT 1 (3300 1900);
DOT 1 (3650 1475);
DOT 1 (4000 1475);
DOT 1 (3650 1900);
DOT 1 (4000 1900);
DOT 1 (2400 3000);
DOT 1 (2750 2575);
DOT 1 (2750 3000);
DOT 1 (3150 2575);
DOT 1 (3150 3000);
DOT 1 (3500 2575);
DOT 1 (3500 3000);
DOT 1 (3850 2575);
DOT 1 (3850 3000);
DOT 1 (4275 1475);
DOT 1 (4125 2575);
DOT 1 (4250 2575);
DOT 1 (4250 3000);
DOT 1 (4600 2575);
DOT 1 (4600 3000);
DOT 1 (5375 2250);
FORCENOTE
ROOM=VDDQ_GHJ_PWR_VR
(-2225 -1125) 0;
DISPLAY LEFT (-2225 -1125);
DISPLAY 1.595745 (-2225 -1125);
PAINT PURPLE (-2225 -1125);
FORCENOTE
BOTTOM SIDE: 805
(-2254 3267) 0;
DISPLAY LEFT (-2254 3267);
DISPLAY 0.638298 (-2254 3267);
PAINT PURPLE (-2254 3267);
FORCENOTE
ROOM=VDDQ_GHJ_CPU1
(-2400 2575) 0;
DISPLAY LEFT (-2400 2575);
DISPLAY 1.021277 (-2400 2575);
PAINT PURPLE (-2400 2575);
FORCENOTE
INPUT FILTER
(-1980 1080) 0;
DISPLAY LEFT (-1980 1080);
PAINT PURPLE (-1980 1080);
FORCENOTE
5MIL SPACING
(-1120 1980) 0;
DISPLAY LEFT (-1120 1980);
DISPLAY 0.808511 (-1120 1980);
PAINT PURPLE (-1120 1980);
FORCENOTE
PVDDQ_ABC VOLTAGE SENSE
(-1845 1780) 0;
DISPLAY LEFT (-1845 1780);
PAINT PURPLE (-1845 1780);
FORCENOTE
10MIL WIDTH
(-1095 2030) 0;
DISPLAY LEFT (-1095 2030);
DISPLAY 0.808511 (-1095 2030);
PAINT PURPLE (-1095 2030);
FORCENOTE
CAD NOTE:
(2875 -525) 0;
DISPLAY LEFT (2875 -525);
DISPLAY 1.021277 (2875 -525);
PAINT PURPLE (2875 -525);
FORCENOTE
PLACE NEAR VR OUTPUT INDUCTORS
(2900 -600) 0;
DISPLAY LEFT (2900 -600);
DISPLAY 1.021277 (2900 -600);
PAINT PURPLE (2900 -600);
FORCENOTE
CAPS TO BE PLACED BETWEEN DIMMS
(2295 3255) 0;
DISPLAY LEFT (2295 3255);
DISPLAY 1.021277 (2295 3255);
PAINT PURPLE (2295 3255);
FORCENOTE
PVDDQ CPU CAVITY CAPS
(-1425 2575) 0;
DISPLAY LEFT (-1425 2575);
DISPLAY 1.021277 (-1425 2575);
PAINT PURPLE (-1425 2575);
FORCENOTE
ROUT AS DIFF PAIR
(-1170 2130) 0;
DISPLAY LEFT (-1170 2130);
DISPLAY 0.808511 (-1170 2130);
PAINT PURPLE (-1170 2130);
FORCENOTE
TOP SIDE: 603
(-1198 3267) 0;
DISPLAY LEFT (-1198 3267);
DISPLAY 0.638298 (-1198 3267);
PAINT PURPLE (-1198 3267);
QUIT
